(kicad_sch
	(version 20250114)
	(generator "eeschema")
	(generator_version "9.0")
	(paper "A3")
	(title_block
		(title "Thunderbolt to 10GbE adapter")
		(date "2026-04-23")
		(rev "1.1.0")
		(company "Antmicro Ltd")
		(comment 1 "www.antmicro.com")
	)
	(bus_alias "10GbE"
		(members "D4+" "D4-" "D3+" "D3-" "D2+" "D2-" "D1+" "D1-")
	)
	(text "X710-AT2 10GbE Interface"
		(exclude_from_sim no)
		(at 215.9 25.4 0)
		(effects
			(font
				(size 2.54 2.54)
				(thickness 0.508)
				(bold yes)
			)
		)
	)
	(text_box "NOTE: Place these 2 resistors close to the controller."
		(exclude_from_sim no)
		(at 234.95 128.27 0)
		(size 54.61 5.08)
		(margins 0.9525 0.9525 0.9525 0.9525)
		(stroke
			(width 0)
			(type solid)
		)
		(fill
			(type none)
		)
		(effects
			(font
				(size 1.27 1.27)
			)
		)
	)
	(junction
		(at 38.1 217.17)
		(diameter 0)
		(color 0 0 0 0)
	)
	(junction
		(at 133.35 223.52)
		(diameter 0)
		(color 0 0 0 0)
	)
	(junction
		(at 261.62 228.6)
		(diameter 0)
		(color 0 0 0 0)
	)
	(junction
		(at 175.26 167.64)
		(diameter 0)
		(color 0 0 0 0)
	)
	(junction
		(at 99.06 170.18)
		(diameter 0)
		(color 0 0 0 0)
	)
	(junction
		(at 175.26 243.84)
		(diameter 0)
		(color 0 0 0 0)
	)
	(junction
		(at 160.02 157.48)
		(diameter 0)
		(color 0 0 0 0)
	)
	(junction
		(at 137.16 157.48)
		(diameter 0)
		(color 0 0 0 0)
	)
	(junction
		(at 58.42 217.17)
		(diameter 0)
		(color 0 0 0 0)
	)
	(junction
		(at 175.26 157.48)
		(diameter 0)
		(color 0 0 0 0)
	)
	(junction
		(at 142.24 226.06)
		(diameter 0)
		(color 0 0 0 0)
	)
	(junction
		(at 167.64 157.48)
		(diameter 0)
		(color 0 0 0 0)
	)
	(junction
		(at 62.23 217.17)
		(diameter 0)
		(color 0 0 0 0)
	)
	(junction
		(at 167.64 170.18)
		(diameter 0)
		(color 0 0 0 0)
	)
	(junction
		(at 144.78 157.48)
		(diameter 0)
		(color 0 0 0 0)
	)
	(junction
		(at 152.4 157.48)
		(diameter 0)
		(color 0 0 0 0)
	)
	(junction
		(at 93.98 167.64)
		(diameter 0)
		(color 0 0 0 0)
	)
	(junction
		(at 261.62 218.44)
		(diameter 0)
		(color 0 0 0 0)
	)
	(junction
		(at 129.54 157.48)
		(diameter 0)
		(color 0 0 0 0)
	)
	(junction
		(at 251.46 231.14)
		(diameter 0)
		(color 0 0 0 0)
	)
	(junction
		(at 53.34 217.17)
		(diameter 0)
		(color 0 0 0 0)
	)
	(no_connect
		(at 193.04 101.6)
	)
	(no_connect
		(at 193.04 111.76)
	)
	(no_connect
		(at 193.04 93.98)
	)
	(no_connect
		(at 238.76 213.36)
	)
	(no_connect
		(at 238.76 200.66)
	)
	(no_connect
		(at 238.76 180.34)
	)
	(no_connect
		(at 238.76 182.88)
	)
	(no_connect
		(at 193.04 218.44)
	)
	(no_connect
		(at 238.76 215.9)
	)
	(no_connect
		(at 193.04 88.9)
	)
	(no_connect
		(at 193.04 210.82)
	)
	(no_connect
		(at 238.76 187.96)
	)
	(no_connect
		(at 193.04 86.36)
	)
	(no_connect
		(at 193.04 213.36)
	)
	(no_connect
		(at 238.76 203.2)
	)
	(no_connect
		(at 238.76 198.12)
	)
	(no_connect
		(at 193.04 205.74)
	)
	(no_connect
		(at 238.76 210.82)
	)
	(no_connect
		(at 193.04 109.22)
	)
	(no_connect
		(at 193.04 104.14)
	)
	(no_connect
		(at 193.04 215.9)
	)
	(no_connect
		(at 193.04 96.52)
	)
	(no_connect
		(at 238.76 205.74)
	)
	(no_connect
		(at 238.76 218.44)
	)
	(no_connect
		(at 238.76 185.42)
	)
	(bus_entry
		(at 261.62 71.12)
		(size -2.54 -2.54)
		(stroke
			(width 0)
			(type default)
		)
	)
	(bus_entry
		(at 261.62 55.88)
		(size -2.54 -2.54)
		(stroke
			(width 0)
			(type default)
		)
	)
	(bus_entry
		(at 170.18 78.74)
		(size 2.54 -2.54)
		(stroke
			(width 0)
			(type default)
		)
	)
	(bus_entry
		(at 261.62 78.74)
		(size -2.54 -2.54)
		(stroke
			(width 0)
			(type default)
		)
	)
	(bus_entry
		(at 261.62 73.66)
		(size -2.54 -2.54)
		(stroke
			(width 0)
			(type default)
		)
	)
	(bus_entry
		(at 69.85 170.18)
		(size 2.54 -2.54)
		(stroke
			(width 0)
			(type default)
		)
	)
	(bus_entry
		(at 170.18 63.5)
		(size 2.54 -2.54)
		(stroke
			(width 0)
			(type default)
		)
	)
	(bus_entry
		(at 170.18 81.28)
		(size 2.54 -2.54)
		(stroke
			(width 0)
			(type default)
		)
	)
	(bus_entry
		(at 261.62 66.04)
		(size -2.54 -2.54)
		(stroke
			(width 0)
			(type default)
		)
	)
	(bus_entry
		(at 170.18 58.42)
		(size 2.54 -2.54)
		(stroke
			(width 0)
			(type default)
		)
	)
	(bus_entry
		(at 69.85 172.72)
		(size 2.54 -2.54)
		(stroke
			(width 0)
			(type default)
		)
	)
	(bus_entry
		(at 261.62 81.28)
		(size -2.54 -2.54)
		(stroke
			(width 0)
			(type default)
		)
	)
	(bus_entry
		(at 170.18 66.04)
		(size 2.54 -2.54)
		(stroke
			(width 0)
			(type default)
		)
	)
	(bus_entry
		(at 261.62 58.42)
		(size -2.54 -2.54)
		(stroke
			(width 0)
			(type default)
		)
	)
	(bus_entry
		(at 170.18 55.88)
		(size 2.54 -2.54)
		(stroke
			(width 0)
			(type default)
		)
	)
	(bus_entry
		(at 170.18 71.12)
		(size 2.54 -2.54)
		(stroke
			(width 0)
			(type default)
		)
	)
	(bus_entry
		(at 170.18 73.66)
		(size 2.54 -2.54)
		(stroke
			(width 0)
			(type default)
		)
	)
	(bus_entry
		(at 261.62 63.5)
		(size -2.54 -2.54)
		(stroke
			(width 0)
			(type default)
		)
	)
	(wire
		(pts
			(xy 251.46 218.44) (xy 261.62 218.44)
		)
		(stroke
			(width 0)
			(type default)
		)
	)
	(wire
		(pts
			(xy 133.35 228.6) (xy 133.35 223.52)
		)
		(stroke
			(width 0)
			(type default)
		)
	)
	(wire
		(pts
			(xy 144.78 182.88) (xy 144.78 165.1)
		)
		(stroke
			(width 0)
			(type default)
		)
	)
	(bus
		(pts
			(xy 261.62 81.28) (xy 261.62 83.82)
		)
		(stroke
			(width 0)
			(type default)
		)
	)
	(wire
		(pts
			(xy 193.04 68.58) (xy 172.72 68.58)
		)
		(stroke
			(width 0)
			(type default)
		)
	)
	(wire
		(pts
			(xy 175.26 167.64) (xy 175.26 165.1)
		)
		(stroke
			(width 0)
			(type default)
		)
	)
	(wire
		(pts
			(xy 62.23 217.17) (xy 62.23 226.06)
		)
		(stroke
			(width 0)
			(type default)
		)
	)
	(wire
		(pts
			(xy 100.33 226.06) (xy 121.92 226.06)
		)
		(stroke
			(width 0)
			(type default)
		)
	)
	(wire
		(pts
			(xy 175.26 251.46) (xy 175.26 254)
		)
		(stroke
			(width 0)
			(type default)
		)
	)
	(wire
		(pts
			(xy 193.04 55.88) (xy 172.72 55.88)
		)
		(stroke
			(width 0)
			(type default)
		)
	)
	(wire
		(pts
			(xy 193.04 60.96) (xy 172.72 60.96)
		)
		(stroke
			(width 0)
			(type default)
		)
	)
	(wire
		(pts
			(xy 121.92 165.1) (xy 121.92 193.04)
		)
		(stroke
			(width 0)
			(type default)
		)
	)
	(wire
		(pts
			(xy 261.62 228.6) (xy 261.62 233.68)
		)
		(stroke
			(width 0)
			(type default)
		)
	)
	(bus
		(pts
			(xy 69.85 172.72) (xy 69.85 175.26)
		)
		(stroke
			(width 0)
			(type default)
		)
	)
	(wire
		(pts
			(xy 142.24 233.68) (xy 142.24 236.22)
		)
		(stroke
			(width 0)
			(type default)
		)
	)
	(wire
		(pts
			(xy 78.74 217.17) (xy 62.23 217.17)
		)
		(stroke
			(width 0)
			(type default)
		)
	)
	(bus
		(pts
			(xy 261.62 73.66) (xy 261.62 78.74)
		)
		(stroke
			(width 0)
			(type default)
		)
	)
	(wire
		(pts
			(xy 121.92 193.04) (xy 193.04 193.04)
		)
		(stroke
			(width 0)
			(type default)
		)
	)
	(wire
		(pts
			(xy 238.76 55.88) (xy 259.08 55.88)
		)
		(stroke
			(width 0)
			(type default)
		)
	)
	(wire
		(pts
			(xy 53.34 217.17) (xy 58.42 217.17)
		)
		(stroke
			(width 0)
			(type default)
		)
	)
	(wire
		(pts
			(xy 58.42 214.63) (xy 58.42 217.17)
		)
		(stroke
			(width 0)
			(type default)
		)
	)
	(bus
		(pts
			(xy 167.64 86.36) (xy 165.1 86.36)
		)
		(stroke
			(width 0)
			(type default)
		)
	)
	(wire
		(pts
			(xy 238.76 109.22) (xy 264.16 109.22)
		)
		(stroke
			(width 0)
			(type default)
		)
	)
	(wire
		(pts
			(xy 142.24 226.06) (xy 142.24 228.6)
		)
		(stroke
			(width 0)
			(type default)
		)
	)
	(wire
		(pts
			(xy 114.3 200.66) (xy 153.67 200.66)
		)
		(stroke
			(width 0)
			(type default)
		)
	)
	(wire
		(pts
			(xy 238.76 228.6) (xy 261.62 228.6)
		)
		(stroke
			(width 0)
			(type default)
		)
	)
	(bus
		(pts
			(xy 261.62 55.88) (xy 261.62 58.42)
		)
		(stroke
			(width 0)
			(type default)
		)
	)
	(wire
		(pts
			(xy 261.62 226.06) (xy 261.62 228.6)
		)
		(stroke
			(width 0)
			(type default)
		)
	)
	(wire
		(pts
			(xy 238.76 63.5) (xy 259.08 63.5)
		)
		(stroke
			(width 0)
			(type default)
		)
	)
	(bus
		(pts
			(xy 170.18 66.04) (xy 170.18 71.12)
		)
		(stroke
			(width 0)
			(type default)
		)
	)
	(wire
		(pts
			(xy 114.3 203.2) (xy 153.67 203.2)
		)
		(stroke
			(width 0)
			(type default)
		)
	)
	(wire
		(pts
			(xy 93.98 167.64) (xy 93.98 172.72)
		)
		(stroke
			(width 0)
			(type default)
		)
	)
	(wire
		(pts
			(xy 193.04 78.74) (xy 172.72 78.74)
		)
		(stroke
			(width 0)
			(type default)
		)
	)
	(wire
		(pts
			(xy 121.92 157.48) (xy 121.92 160.02)
		)
		(stroke
			(width 0)
			(type default)
		)
	)
	(wire
		(pts
			(xy 238.76 111.76) (xy 255.27 111.76)
		)
		(stroke
			(width 0)
			(type default)
		)
	)
	(bus
		(pts
			(xy 264.16 86.36) (xy 261.62 83.82)
		)
		(stroke
			(width 0)
			(type default)
		)
	)
	(wire
		(pts
			(xy 238.76 60.96) (xy 259.08 60.96)
		)
		(stroke
			(width 0)
			(type default)
		)
	)
	(wire
		(pts
			(xy 238.76 172.72) (xy 252.73 172.72)
		)
		(stroke
			(width 0)
			(type default)
		)
	)
	(wire
		(pts
			(xy 251.46 226.06) (xy 251.46 231.14)
		)
		(stroke
			(width 0)
			(type default)
		)
	)
	(bus
		(pts
			(xy 167.64 86.36) (xy 170.18 83.82)
		)
		(stroke
			(width 0)
			(type default)
		)
	)
	(bus
		(pts
			(xy 170.18 81.28) (xy 170.18 83.82)
		)
		(stroke
			(width 0)
			(type default)
		)
	)
	(wire
		(pts
			(xy 193.04 63.5) (xy 172.72 63.5)
		)
		(stroke
			(width 0)
			(type default)
		)
	)
	(wire
		(pts
			(xy 78.74 223.52) (xy 78.74 217.17)
		)
		(stroke
			(width 0)
			(type default)
		)
	)
	(wire
		(pts
			(xy 261.62 218.44) (xy 261.62 220.98)
		)
		(stroke
			(width 0)
			(type default)
		)
	)
	(wire
		(pts
			(xy 251.46 238.76) (xy 251.46 241.3)
		)
		(stroke
			(width 0)
			(type default)
		)
	)
	(wire
		(pts
			(xy 93.98 180.34) (xy 93.98 177.8)
		)
		(stroke
			(width 0)
			(type default)
		)
	)
	(wire
		(pts
			(xy 255.27 119.38) (xy 255.27 121.92)
		)
		(stroke
			(width 0)
			(type default)
		)
	)
	(wire
		(pts
			(xy 152.4 160.02) (xy 152.4 157.48)
		)
		(stroke
			(width 0)
			(type default)
		)
	)
	(wire
		(pts
			(xy 160.02 157.48) (xy 152.4 157.48)
		)
		(stroke
			(width 0)
			(type default)
		)
	)
	(wire
		(pts
			(xy 81.28 228.6) (xy 78.74 228.6)
		)
		(stroke
			(width 0)
			(type default)
		)
	)
	(wire
		(pts
			(xy 238.76 175.26) (xy 252.73 175.26)
		)
		(stroke
			(width 0)
			(type default)
		)
	)
	(wire
		(pts
			(xy 261.62 215.9) (xy 261.62 218.44)
		)
		(stroke
			(width 0)
			(type default)
		)
	)
	(wire
		(pts
			(xy 175.26 167.64) (xy 193.04 167.64)
		)
		(stroke
			(width 0)
			(type default)
		)
	)
	(wire
		(pts
			(xy 48.26 217.17) (xy 53.34 217.17)
		)
		(stroke
			(width 0)
			(type default)
		)
	)
	(wire
		(pts
			(xy 78.74 228.6) (xy 78.74 236.22)
		)
		(stroke
			(width 0)
			(type default)
		)
	)
	(wire
		(pts
			(xy 127 226.06) (xy 142.24 226.06)
		)
		(stroke
			(width 0)
			(type default)
		)
	)
	(wire
		(pts
			(xy 238.76 231.14) (xy 251.46 231.14)
		)
		(stroke
			(width 0)
			(type default)
		)
	)
	(bus
		(pts
			(xy 261.62 78.74) (xy 261.62 81.28)
		)
		(stroke
			(width 0)
			(type default)
		)
	)
	(wire
		(pts
			(xy 238.76 170.18) (xy 252.73 170.18)
		)
		(stroke
			(width 0)
			(type default)
		)
	)
	(wire
		(pts
			(xy 238.76 76.2) (xy 259.08 76.2)
		)
		(stroke
			(width 0)
			(type default)
		)
	)
	(wire
		(pts
			(xy 53.34 229.87) (xy 53.34 236.22)
		)
		(stroke
			(width 0)
			(type default)
		)
	)
	(bus
		(pts
			(xy 170.18 73.66) (xy 170.18 78.74)
		)
		(stroke
			(width 0)
			(type default)
		)
	)
	(wire
		(pts
			(xy 129.54 190.5) (xy 193.04 190.5)
		)
		(stroke
			(width 0)
			(type default)
		)
	)
	(bus
		(pts
			(xy 170.18 71.12) (xy 170.18 73.66)
		)
		(stroke
			(width 0)
			(type default)
		)
	)
	(wire
		(pts
			(xy 127 223.52) (xy 133.35 223.52)
		)
		(stroke
			(width 0)
			(type default)
		)
	)
	(wire
		(pts
			(xy 110.49 167.64) (xy 175.26 167.64)
		)
		(stroke
			(width 0)
			(type default)
		)
	)
	(wire
		(pts
			(xy 152.4 177.8) (xy 152.4 165.1)
		)
		(stroke
			(width 0)
			(type default)
		)
	)
	(bus
		(pts
			(xy 170.18 55.88) (xy 170.18 58.42)
		)
		(stroke
			(width 0)
			(type default)
		)
	)
	(bus
		(pts
			(xy 261.62 66.04) (xy 261.62 71.12)
		)
		(stroke
			(width 0)
			(type default)
		)
	)
	(wire
		(pts
			(xy 167.64 165.1) (xy 167.64 170.18)
		)
		(stroke
			(width 0)
			(type default)
		)
	)
	(wire
		(pts
			(xy 152.4 157.48) (xy 144.78 157.48)
		)
		(stroke
			(width 0)
			(type default)
		)
	)
	(wire
		(pts
			(xy 251.46 231.14) (xy 251.46 233.68)
		)
		(stroke
			(width 0)
			(type default)
		)
	)
	(wire
		(pts
			(xy 72.39 167.64) (xy 93.98 167.64)
		)
		(stroke
			(width 0)
			(type default)
		)
	)
	(wire
		(pts
			(xy 81.28 226.06) (xy 69.85 226.06)
		)
		(stroke
			(width 0)
			(type default)
		)
	)
	(bus
		(pts
			(xy 261.62 63.5) (xy 261.62 66.04)
		)
		(stroke
			(width 0)
			(type default)
		)
	)
	(wire
		(pts
			(xy 175.26 243.84) (xy 181.61 243.84)
		)
		(stroke
			(width 0)
			(type default)
		)
	)
	(wire
		(pts
			(xy 160.02 175.26) (xy 193.04 175.26)
		)
		(stroke
			(width 0)
			(type default)
		)
	)
	(wire
		(pts
			(xy 264.16 119.38) (xy 264.16 121.92)
		)
		(stroke
			(width 0)
			(type default)
		)
	)
	(wire
		(pts
			(xy 129.54 157.48) (xy 129.54 160.02)
		)
		(stroke
			(width 0)
			(type default)
		)
	)
	(wire
		(pts
			(xy 133.35 223.52) (xy 163.83 223.52)
		)
		(stroke
			(width 0)
			(type default)
		)
	)
	(wire
		(pts
			(xy 38.1 217.17) (xy 43.18 217.17)
		)
		(stroke
			(width 0)
			(type default)
		)
	)
	(wire
		(pts
			(xy 261.62 238.76) (xy 261.62 241.3)
		)
		(stroke
			(width 0)
			(type default)
		)
	)
	(wire
		(pts
			(xy 38.1 214.63) (xy 38.1 217.17)
		)
		(stroke
			(width 0)
			(type default)
		)
	)
	(wire
		(pts
			(xy 160.02 175.26) (xy 160.02 165.1)
		)
		(stroke
			(width 0)
			(type default)
		)
	)
	(wire
		(pts
			(xy 175.26 154.94) (xy 175.26 157.48)
		)
		(stroke
			(width 0)
			(type default)
		)
	)
	(wire
		(pts
			(xy 175.26 157.48) (xy 167.64 157.48)
		)
		(stroke
			(width 0)
			(type default)
		)
	)
	(wire
		(pts
			(xy 238.76 78.74) (xy 259.08 78.74)
		)
		(stroke
			(width 0)
			(type default)
		)
	)
	(wire
		(pts
			(xy 238.76 167.64) (xy 252.73 167.64)
		)
		(stroke
			(width 0)
			(type default)
		)
	)
	(wire
		(pts
			(xy 99.06 170.18) (xy 99.06 172.72)
		)
		(stroke
			(width 0)
			(type default)
		)
	)
	(wire
		(pts
			(xy 238.76 53.34) (xy 259.08 53.34)
		)
		(stroke
			(width 0)
			(type default)
		)
	)
	(wire
		(pts
			(xy 142.24 226.06) (xy 153.67 226.06)
		)
		(stroke
			(width 0)
			(type default)
		)
	)
	(bus
		(pts
			(xy 261.62 71.12) (xy 261.62 73.66)
		)
		(stroke
			(width 0)
			(type default)
		)
	)
	(wire
		(pts
			(xy 100.33 223.52) (xy 121.92 223.52)
		)
		(stroke
			(width 0)
			(type default)
		)
	)
	(wire
		(pts
			(xy 81.28 223.52) (xy 78.74 223.52)
		)
		(stroke
			(width 0)
			(type default)
		)
	)
	(wire
		(pts
			(xy 175.26 160.02) (xy 175.26 157.48)
		)
		(stroke
			(width 0)
			(type default)
		)
	)
	(wire
		(pts
			(xy 167.64 170.18) (xy 193.04 170.18)
		)
		(stroke
			(width 0)
			(type default)
		)
	)
	(wire
		(pts
			(xy 158.75 203.2) (xy 193.04 203.2)
		)
		(stroke
			(width 0)
			(type default)
		)
	)
	(bus
		(pts
			(xy 264.16 86.36) (xy 266.7 86.36)
		)
		(stroke
			(width 0)
			(type default)
		)
	)
	(wire
		(pts
			(xy 99.06 180.34) (xy 99.06 177.8)
		)
		(stroke
			(width 0)
			(type default)
		)
	)
	(wire
		(pts
			(xy 175.26 241.3) (xy 175.26 243.84)
		)
		(stroke
			(width 0)
			(type default)
		)
	)
	(wire
		(pts
			(xy 137.16 157.48) (xy 129.54 157.48)
		)
		(stroke
			(width 0)
			(type default)
		)
	)
	(wire
		(pts
			(xy 129.54 165.1) (xy 129.54 190.5)
		)
		(stroke
			(width 0)
			(type default)
		)
	)
	(wire
		(pts
			(xy 264.16 109.22) (xy 264.16 114.3)
		)
		(stroke
			(width 0)
			(type default)
		)
	)
	(wire
		(pts
			(xy 144.78 182.88) (xy 193.04 182.88)
		)
		(stroke
			(width 0)
			(type default)
		)
	)
	(wire
		(pts
			(xy 251.46 218.44) (xy 251.46 220.98)
		)
		(stroke
			(width 0)
			(type default)
		)
	)
	(bus
		(pts
			(xy 170.18 58.42) (xy 170.18 63.5)
		)
		(stroke
			(width 0)
			(type default)
		)
	)
	(bus
		(pts
			(xy 261.62 58.42) (xy 261.62 63.5)
		)
		(stroke
			(width 0)
			(type default)
		)
	)
	(wire
		(pts
			(xy 72.39 170.18) (xy 99.06 170.18)
		)
		(stroke
			(width 0)
			(type default)
		)
	)
	(wire
		(pts
			(xy 133.35 236.22) (xy 133.35 233.68)
		)
		(stroke
			(width 0)
			(type default)
		)
	)
	(wire
		(pts
			(xy 158.75 200.66) (xy 193.04 200.66)
		)
		(stroke
			(width 0)
			(type default)
		)
	)
	(wire
		(pts
			(xy 193.04 76.2) (xy 172.72 76.2)
		)
		(stroke
			(width 0)
			(type default)
		)
	)
	(bus
		(pts
			(xy 170.18 63.5) (xy 170.18 66.04)
		)
		(stroke
			(width 0)
			(type default)
		)
	)
	(wire
		(pts
			(xy 238.76 71.12) (xy 259.08 71.12)
		)
		(stroke
			(width 0)
			(type default)
		)
	)
	(wire
		(pts
			(xy 193.04 71.12) (xy 172.72 71.12)
		)
		(stroke
			(width 0)
			(type default)
		)
	)
	(bus
		(pts
			(xy 69.85 170.18) (xy 69.85 172.72)
		)
		(stroke
			(width 0)
			(type default)
		)
	)
	(wire
		(pts
			(xy 64.77 226.06) (xy 62.23 226.06)
		)
		(stroke
			(width 0)
			(type default)
		)
	)
	(wire
		(pts
			(xy 58.42 217.17) (xy 62.23 217.17)
		)
		(stroke
			(width 0)
			(type default)
		)
	)
	(wire
		(pts
			(xy 158.75 198.12) (xy 193.04 198.12)
		)
		(stroke
			(width 0)
			(type default)
		)
	)
	(wire
		(pts
			(xy 137.16 185.42) (xy 137.16 165.1)
		)
		(stroke
			(width 0)
			(type default)
		)
	)
	(wire
		(pts
			(xy 160.02 157.48) (xy 160.02 160.02)
		)
		(stroke
			(width 0)
			(type default)
		)
	)
	(wire
		(pts
			(xy 38.1 229.87) (xy 38.1 236.22)
		)
		(stroke
			(width 0)
			(type default)
		)
	)
	(wire
		(pts
			(xy 167.64 157.48) (xy 160.02 157.48)
		)
		(stroke
			(width 0)
			(type default)
		)
	)
	(wire
		(pts
			(xy 167.64 157.48) (xy 167.64 160.02)
		)
		(stroke
			(width 0)
			(type default)
		)
	)
	(wire
		(pts
			(xy 181.61 243.84) (xy 181.61 231.14)
		)
		(stroke
			(width 0)
			(type default)
		)
	)
	(bus
		(pts
			(xy 67.31 177.8) (xy 69.85 175.26)
		)
		(stroke
			(width 0)
			(type default)
		)
	)
	(wire
		(pts
			(xy 110.49 170.18) (xy 167.64 170.18)
		)
		(stroke
			(width 0)
			(type default)
		)
	)
	(wire
		(pts
			(xy 38.1 224.79) (xy 38.1 217.17)
		)
		(stroke
			(width 0)
			(type default)
		)
	)
	(wire
		(pts
			(xy 137.16 185.42) (xy 193.04 185.42)
		)
		(stroke
			(width 0)
			(type default)
		)
	)
	(wire
		(pts
			(xy 168.91 223.52) (xy 193.04 223.52)
		)
		(stroke
			(width 0)
			(type default)
		)
	)
	(wire
		(pts
			(xy 255.27 111.76) (xy 255.27 114.3)
		)
		(stroke
			(width 0)
			(type default)
		)
	)
	(wire
		(pts
			(xy 114.3 198.12) (xy 153.67 198.12)
		)
		(stroke
			(width 0)
			(type default)
		)
	)
	(wire
		(pts
			(xy 152.4 177.8) (xy 193.04 177.8)
		)
		(stroke
			(width 0)
			(type default)
		)
	)
	(wire
		(pts
			(xy 144.78 157.48) (xy 137.16 157.48)
		)
		(stroke
			(width 0)
			(type default)
		)
	)
	(wire
		(pts
			(xy 238.76 68.58) (xy 259.08 68.58)
		)
		(stroke
			(width 0)
			(type default)
		)
	)
	(wire
		(pts
			(xy 93.98 167.64) (xy 105.41 167.64)
		)
		(stroke
			(width 0)
			(type default)
		)
	)
	(wire
		(pts
			(xy 181.61 231.14) (xy 193.04 231.14)
		)
		(stroke
			(width 0)
			(type default)
		)
	)
	(bus
		(pts
			(xy 170.18 78.74) (xy 170.18 81.28)
		)
		(stroke
			(width 0)
			(type default)
		)
	)
	(wire
		(pts
			(xy 193.04 53.34) (xy 172.72 53.34)
		)
		(stroke
			(width 0)
			(type default)
		)
	)
	(wire
		(pts
			(xy 137.16 157.48) (xy 137.16 160.02)
		)
		(stroke
			(width 0)
			(type default)
		)
	)
	(bus
		(pts
			(xy 64.77 177.8) (xy 67.31 177.8)
		)
		(stroke
			(width 0)
			(type default)
		)
	)
	(wire
		(pts
			(xy 144.78 160.02) (xy 144.78 157.48)
		)
		(stroke
			(width 0)
			(type default)
		)
	)
	(wire
		(pts
			(xy 158.75 226.06) (xy 193.04 226.06)
		)
		(stroke
			(width 0)
			(type default)
		)
	)
	(wire
		(pts
			(xy 175.26 233.68) (xy 175.26 236.22)
		)
		(stroke
			(width 0)
			(type default)
		)
	)
	(wire
		(pts
			(xy 175.26 243.84) (xy 175.26 246.38)
		)
		(stroke
			(width 0)
			(type default)
		)
	)
	(wire
		(pts
			(xy 99.06 170.18) (xy 105.41 170.18)
		)
		(stroke
			(width 0)
			(type default)
		)
	)
	(wire
		(pts
			(xy 53.34 217.17) (xy 53.34 224.79)
		)
		(stroke
			(width 0)
			(type default)
		)
	)
	(wire
		(pts
			(xy 129.54 157.48) (xy 121.92 157.48)
		)
		(stroke
			(width 0)
			(type default)
		)
	)
	(table
		(column_count 2)
		(border
			(external yes)
			(header yes)
			(stroke
				(width 0)
				(type solid)
			)
		)
		(separators
			(rows yes)
			(cols yes)
			(stroke
				(width 0)
				(type solid)
			)
		)
		(column_widths 41.91 41.91)
		(row_heights 5.08 3.81 2.54 2.54 3.81 2.54 2.54)
		(cells
			(table_cell "BASE-T PHY MDI Pair Swap Configuration\n"
				(exclude_from_sim no)
				(at 276.86 218.44 0)
				(size 83.82 5.08)
				(margins 0.9525 0.9525 0.9525 0.9525)
				(span 2 1)
				(fill
					(type none)
				)
				(effects
					(font
						(size 1.27 1.27)
						(thickness 0.254)
						(bold yes)
					)
				)
			)
			(table_cell "rgb(135, 135, 135)"
				(exclude_from_sim no)
				(at 318.77 218.44 0)
				(size 41.91 5.08)
				(margins 0.9525 0.9525 0.9525 0.9525)
				(span 0 0)
				(fill
					(type none)
				)
				(effects
					(font
						(size 1.27 1.27)
					)
					(justify left top)
				)
			)
			(table_cell "Port 0"
				(exclude_from_sim no)
				(at 276.86 223.52 0)
				(size 83.82 3.81)
				(margins 0.9525 0.9525 0.9525 0.9525)
				(span 2 1)
				(fill
					(type none)
				)
				(effects
					(font
						(size 1.27 1.27)
					)
				)
			)
			(table_cell "rgb(135, 135, 135)"
				(exclude_from_sim no)
				(at 318.77 223.52 0)
				(size 41.91 3.81)
				(margins 0.9525 0.9525 0.9525 0.9525)
				(span 0 0)
				(fill
					(type none)
				)
				(effects
					(font
						(size 1.27 1.27)
					)
					(justify left top)
				)
			)
			(table_cell "TPIN_5 = 0 (Pull down to GND with 0R) "
				(exclude_from_sim no)
				(at 276.86 227.33 0)
				(size 41.91 2.54)
				(margins 0.9525 0.9525 0.9525 0.9525)
				(span 1 1)
				(fill
					(type none)
				)
				(effects
					(font
						(size 1.27 1.27)
					)
				)
			)
			(table_cell "MDI pair swap"
				(exclude_from_sim no)
				(at 318.77 227.33 0)
				(size 41.91 2.54)
				(margins 0.9525 0.9525 0.9525 0.9525)
				(span 1 1)
				(fill
					(type none)
				)
				(effects
					(font
						(size 1.27 1.27)
					)
				)
			)
			(table_cell "TPIN_5 = 1 (Pull up to 1V88 with 1k) "
				(exclude_from_sim no)
				(at 276.86 229.87 0)
				(size 41.91 2.54)
				(margins 0.9525 0.9525 0.9525 0.9525)
				(span 1 1)
				(fill
					(type none)
				)
				(effects
					(font
						(size 1.27 1.27)
					)
				)
			)
			(table_cell "No MDI pair swap"
				(exclude_from_sim no)
				(at 318.77 229.87 0)
				(size 41.91 2.54)
				(margins 0.9525 0.9525 0.9525 0.9525)
				(span 1 1)
				(fill
					(type none)
				)
				(effects
					(font
						(size 1.27 1.27)
					)
				)
			)
			(table_cell "Port 1"
				(exclude_from_sim no)
				(at 276.86 232.41 0)
				(size 83.82 3.81)
				(margins 0.9525 0.9525 0.9525 0.9525)
				(span 2 1)
				(fill
					(type none)
				)
				(effects
					(font
						(size 1.27 1.27)
					)
				)
			)
			(table_cell "rgb(135, 135, 135)"
				(exclude_from_sim no)
				(at 318.77 232.41 0)
				(size 41.91 3.81)
				(margins 0.9525 0.9525 0.9525 0.9525)
				(span 0 0)
				(fill
					(type none)
				)
				(effects
					(font
						(size 1.27 1.27)
					)
					(justify left top)
				)
			)
			(table_cell "TPIN_3 = 0 (Pull down to GND with 0R) "
				(exclude_from_sim no)
				(at 276.86 236.22 0)
				(size 41.91 2.54)
				(margins 0.9525 0.9525 0.9525 0.9525)
				(span 1 1)
				(fill
					(type none)
				)
				(effects
					(font
						(size 1.27 1.27)
					)
				)
			)
			(table_cell "No MDI pair swap"
				(exclude_from_sim no)
				(at 318.77 236.22 0)
				(size 41.91 2.54)
				(margins 0.9525 0.9525 0.9525 0.9525)
				(span 1 1)
				(fill
					(type none)
				)
				(effects
					(font
						(size 1.27 1.27)
					)
				)
			)
			(table_cell "TPIN_3 = 1 (Pull up to 1V88 with 1k) "
				(exclude_from_sim no)
				(at 276.86 238.76 0)
				(size 41.91 2.54)
				(margins 0.9525 0.9525 0.9525 0.9525)
				(span 1 1)
				(fill
					(type none)
				)
				(effects
					(font
						(size 1.27 1.27)
					)
				)
			)
			(table_cell "MDI pair swap"
				(exclude_from_sim no)
				(at 318.77 238.76 0)
				(size 41.91 2.54)
				(margins 0.9525 0.9525 0.9525 0.9525)
				(span 1 1)
				(fill
					(type none)
				)
				(effects
					(font
						(size 1.27 1.27)
					)
				)
			)
		)
	)
	(label "MDC1_SCL1"
		(at 190.5 177.8 180)
		(effects
			(font
				(size 1.27 1.27)
			)
			(justify right bottom)
		)
	)
	(label "MDIO0_I2C0.MDIO"
		(at 73.66 167.64 0)
		(effects
			(font
				(size 1.27 1.27)
			)
			(justify left bottom)
		)
	)
	(label "~{P1_INT_R}"
		(at 190.5 203.2 180)
		(effects
			(font
				(size 1.27 1.27)
			)
			(justify right bottom)
		)
	)
	(label "TPIN_5"
		(at 241.3 228.6 0)
		(effects
			(font
				(size 1.27 1.27)
			)
			(justify left bottom)
		)
	)
	(label "Ethernet_P1.D2+"
		(at 241.3 60.96 0)
		(effects
			(font
				(size 1.27 1.27)
			)
			(justify left bottom)
		)
	)
	(label "25MHZ_OSC_AC.+"
		(at 151.13 223.52 180)
		(effects
			(font
				(size 1.27 1.27)
			)
			(justify right bottom)
		)
	)
	(label "BIAS_RDAC"
		(at 241.3 109.22 0)
		(effects
			(font
				(size 1.27 1.27)
			)
			(justify left bottom)
		)
	)
	(label "Ethernet_P0.D2+"
		(at 190.5 60.96 180)
		(effects
			(font
				(size 1.27 1.27)
			)
			(justify right bottom)
		)
	)
	(label "MDIO1_SDA1"
		(at 190.5 175.26 180)
		(effects
			(font
				(size 1.27 1.27)
			)
			(justify right bottom)
		)
	)
	(label "Ethernet_P0.D3-"
		(at 190.5 71.12 180)
		(effects
			(font
				(size 1.27 1.27)
			)
			(justify right bottom)
		)
	)
	(label "TPIN_3"
		(at 241.3 231.14 0)
		(effects
			(font
				(size 1.27 1.27)
			)
			(justify left bottom)
		)
	)
	(label "Ethernet_P0.D1+"
		(at 190.5 53.34 180)
		(effects
			(font
				(size 1.27 1.27)
			)
			(justify right bottom)
		)
	)
	(label "25MHZ_OSC_R.-"
		(at 116.84 226.06 180)
		(effects
			(font
				(size 1.27 1.27)
			)
			(justify right bottom)
		)
	)
	(label "Ethernet_P1.D4-"
		(at 241.3 78.74 0)
		(effects
			(font
				(size 1.27 1.27)
			)
			(justify left bottom)
		)
	)
	(label "Ethernet_P1.D1-"
		(at 241.3 55.88 0)
		(effects
			(font
				(size 1.27 1.27)
			)
			(justify left bottom)
		)
	)
	(label "25MHZ_OSC_R.+"
		(at 116.84 223.52 180)
		(effects
			(font
				(size 1.27 1.27)
			)
			(justify right bottom)
		)
	)
	(label "Ethernet_P0.D1-"
		(at 190.5 55.88 180)
		(effects
			(font
				(size 1.27 1.27)
			)
			(justify right bottom)
		)
	)
	(label "Ethernet_P1.D3+"
		(at 241.3 68.58 0)
		(effects
			(font
				(size 1.27 1.27)
			)
			(justify left bottom)
		)
	)
	(label "3V3_OSC"
		(at 78.74 217.17 180)
		(effects
			(font
				(size 1.27 1.27)
			)
			(justify right bottom)
		)
	)
	(label "OSC_SEL"
		(at 190.5 231.14 180)
		(effects
			(font
				(size 1.27 1.27)
			)
			(justify right bottom)
		)
	)
	(label "Ethernet_P0.D2-"
		(at 190.5 63.5 180)
		(effects
			(font
				(size 1.27 1.27)
			)
			(justify right bottom)
		)
	)
	(label "MDC3_SCL3"
		(at 190.5 193.04 180)
		(effects
			(font
				(size 1.27 1.27)
			)
			(justify right bottom)
		)
	)
	(label "Ethernet_P1.D2-"
		(at 241.3 63.5 0)
		(effects
			(font
				(size 1.27 1.27)
			)
			(justify left bottom)
		)
	)
	(label "25MHZ_OSC.+"
		(at 190.5 223.52 180)
		(effects
			(font
				(size 1.27 1.27)
			)
			(justify right bottom)
		)
	)
	(label "Ethernet_P1.D1+"
		(at 241.3 53.34 0)
		(effects
			(font
				(size 1.27 1.27)
			)
			(justify left bottom)
		)
	)
	(label "Ethernet_P0.D3+"
		(at 190.5 68.58 180)
		(effects
			(font
				(size 1.27 1.27)
			)
			(justify right bottom)
		)
	)
	(label "MDC2_SCL2"
		(at 190.5 185.42 180)
		(effects
			(font
				(size 1.27 1.27)
			)
			(justify right bottom)
		)
	)
	(label "MDIO2_SDA2"
		(at 190.5 182.88 180)
		(effects
			(font
				(size 1.27 1.27)
			)
			(justify right bottom)
		)
	)
	(label "Ethernet_P0.D4+"
		(at 190.5 76.2 180)
		(effects
			(font
				(size 1.27 1.27)
			)
			(justify right bottom)
		)
	)
	(label "MDIO3_SDA3"
		(at 190.5 190.5 180)
		(effects
			(font
				(size 1.27 1.27)
			)
			(justify right bottom)
		)
	)
	(label "MDC0_SCL0"
		(at 190.5 170.18 180)
		(effects
			(font
				(size 1.27 1.27)
			)
			(justify right bottom)
		)
	)
	(label "~{PHY_RESET_3V3_R}"
		(at 190.5 198.12 180)
		(effects
			(font
				(size 1.27 1.27)
			)
			(justify right bottom)
		)
	)
	(label "Ethernet_P0.D4-"
		(at 190.5 78.74 180)
		(effects
			(font
				(size 1.27 1.27)
			)
			(justify right bottom)
		)
	)
	(label "~{P0_INT_R}"
		(at 190.5 200.66 180)
		(effects
			(font
				(size 1.27 1.27)
			)
			(justify right bottom)
		)
	)
	(label "Ethernet_P1.D3-"
		(at 241.3 71.12 0)
		(effects
			(font
				(size 1.27 1.27)
			)
			(justify left bottom)
		)
	)
	(label "EN_OSC"
		(at 78.74 226.06 180)
		(effects
			(font
				(size 1.27 1.27)
			)
			(justify right bottom)
		)
	)
	(label "25MHZ_OSC_AC.-"
		(at 151.13 226.06 180)
		(effects
			(font
				(size 1.27 1.27)
			)
			(justify right bottom)
		)
	)
	(label "Ethernet_P1.D4+"
		(at 241.3 76.2 0)
		(effects
			(font
				(size 1.27 1.27)
			)
			(justify left bottom)
		)
	)
	(label "MDIO0_I2C0.MDC"
		(at 73.66 170.18 0)
		(effects
			(font
				(size 1.27 1.27)
			)
			(justify left bottom)
		)
	)
	(label "25MHZ_OSC.-"
		(at 190.5 226.06 180)
		(effects
			(font
				(size 1.27 1.27)
			)
			(justify right bottom)
		)
	)
	(label "MDIO0_SDA0"
		(at 190.5 167.64 180)
		(effects
			(font
				(size 1.27 1.27)
			)
			(justify right bottom)
		)
	)
	(label "RESCAL_RES_P"
		(at 241.3 111.76 0)
		(effects
			(font
				(size 1.27 1.27)
			)
			(justify left bottom)
		)
	)
	(hierarchical_label "~{P0_LED_ACT}"
		(shape output)
		(at 252.73 167.64 0)
		(effects
			(font
				(size 1.27 1.27)
			)
			(justify left)
		)
	)
	(hierarchical_label "~{P1_INT}"
		(shape input)
		(at 114.3 203.2 180)
		(effects
			(font
				(size 1.27 1.27)
			)
			(justify right)
		)
	)
	(hierarchical_label "~{PHY_RESET_3V3}"
		(shape output)
		(at 114.3 198.12 180)
		(effects
			(font
				(size 1.27 1.27)
			)
			(justify right)
		)
	)
	(hierarchical_label "Ethernet_P0{10GbE}"
		(shape bidirectional)
		(at 165.1 86.36 180)
		(effects
			(font
				(size 1.27 1.27)
			)
			(justify right)
		)
	)
	(hierarchical_label "MDIO0_I2C0{MDIO}"
		(shape bidirectional)
		(at 64.77 177.8 180)
		(effects
			(font
				(size 1.27 1.27)
			)
			(justify right)
		)
	)
	(hierarchical_label "~{P0_INT}"
		(shape input)
		(at 114.3 200.66 180)
		(effects
			(font
				(size 1.27 1.27)
			)
			(justify right)
		)
	)
	(hierarchical_label "~{P1_LED_LINK_10G}"
		(shape output)
		(at 252.73 175.26 0)
		(effects
			(font
				(size 1.27 1.27)
			)
			(justify left)
		)
	)
	(hierarchical_label "~{P0_LED_LINK_10G}"
		(shape output)
		(at 252.73 170.18 0)
		(effects
			(font
				(size 1.27 1.27)
			)
			(justify left)
		)
	)
	(hierarchical_label "~{P1_LED_ACT}"
		(shape output)
		(at 252.73 172.72 0)
		(effects
			(font
				(size 1.27 1.27)
			)
			(justify left)
		)
	)
	(hierarchical_label "Ethernet_P1{10GbE}"
		(shape bidirectional)
		(at 266.7 86.36 0)
		(effects
			(font
				(size 1.27 1.27)
			)
			(justify left)
		)
	)
	(rule_area
		(polyline
			(pts
				(xy 288.29 49.53) (xy 240.03 49.53) (xy 240.03 88.9) (xy 288.29 88.9)
			)
			(stroke
				(width 0)
				(type dash)
			)
			(fill
				(type none)
			)
		)
	)
	(rule_area
		(polyline
			(pts
				(xy 173.99 228.6) (xy 173.99 219.71) (xy 100.33 219.71) (xy 100.33 228.6)
			)
			(stroke
				(width 0)
				(type dash)
			)
			(fill
				(type none)
			)
		)
	)
	(rule_area
		(polyline
			(pts
				(xy 191.77 49.53) (xy 143.51 49.53) (xy 143.51 88.9) (xy 191.77 88.9)
			)
			(stroke
				(width 0)
				(type dash)
			)
			(fill
				(type none)
			)
		)
	)
	(netclass_flag ""
		(length 2.54)
		(shape round)
		(at 288.29 49.53 0)
		(fields_autoplaced yes)
		(effects
			(font
				(size 1.27 1.27)
			)
			(justify left bottom)
		)
		(property "Netclass" "100Ohm-diff_10GbE"
			(at 287.5915 46.99 0)
			(effects
				(font
					(size 1.27 1.27)
				)
				(justify right)
			)
		)
		(property "Component Class" ""
			(at 511.81 -3.81 0)
			(effects
				(font
					(size 1.27 1.27)
					(italic yes)
				)
				(justify left)
			)
		)
	)
	(netclass_flag ""
		(length 2.54)
		(shape round)
		(at 173.99 219.71 0)
		(fields_autoplaced yes)
		(effects
			(font
				(size 1.27 1.27)
			)
			(justify left bottom)
		)
		(property "Netclass" "85Ohm-diff_PCIe"
			(at 173.2915 217.17 0)
			(effects
				(font
					(size 1.27 1.27)
				)
				(justify right)
			)
		)
		(property "Component Class" ""
			(at -49.53 166.37 0)
			(effects
				(font
					(size 1.27 1.27)
					(italic yes)
				)
				(justify right)
			)
		)
	)
	(netclass_flag ""
		(length 2.54)
		(shape round)
		(at 143.51 49.53 0)
		(fields_autoplaced yes)
		(effects
			(font
				(size 1.27 1.27)
			)
			(justify left bottom)
		)
		(property "Netclass" "100Ohm-diff_10GbE"
			(at 144.2085 46.99 0)
			(effects
				(font
					(size 1.27 1.27)
				)
				(justify left)
			)
		)
		(property "Component Class" ""
			(at -80.01 -3.81 0)
			(effects
				(font
					(size 1.27 1.27)
					(italic yes)
				)
				(justify right)
			)
		)
	)
	(symbol
		(lib_id "antmicropower:GND")
		(at 264.16 121.92 0)
		(unit 1)
		(exclude_from_sim no)
		(in_bom yes)
		(on_board yes)
		(dnp no)
		(property "Reference" "#PWR0428"
			(at 273.05 124.46 0)
			(effects
				(font
					(size 1.27 1.27)
					(thickness 0.15)
				)
				(justify left bottom)
				(hide yes)
			)
		)
		(property "Value" "GND"
			(at 264.16 125.73 0)
			(effects
				(font
					(size 1.27 1.27)
					(thickness 0.15)
				)
			)
		)
		(property "Footprint" ""
			(at 273.05 129.54 0)
			(effects
				(font
					(size 1.27 1.27)
					(thickness 0.15)
				)
				(justify left bottom)
				(hide yes)
			)
		)
		(property "Datasheet" ""
			(at 273.05 134.62 0)
			(effects
				(font
					(size 1.27 1.27)
					(thickness 0.15)
				)
				(justify left bottom)
				(hide yes)
			)
		)
		(property "Description" ""
			(at 264.16 121.92 0)
			(effects
				(font
					(size 1.27 1.27)
				)
				(hide yes)
			)
		)
		(property "Author" "Antmicro"
			(at 273.05 129.54 0)
			(effects
				(font
					(size 1.27 1.27)
					(thickness 0.15)
				)
				(justify left bottom)
				(hide yes)
			)
		)
		(property "License" "Apache-2.0"
			(at 273.05 132.08 0)
			(effects
				(font
					(size 1.27 1.27)
					(thickness 0.15)
				)
				(justify left bottom)
				(hide yes)
			)
		)
		(pin "1"
		)
		(instances
			(project "OCuLink to 10GbE adapter"
				(path ""
					(reference "#PWR0251")
					(unit 1)
				)
			)
			(project "thunderbolt-to-10gbe-adapter"
				(path ""
					(reference "#PWR0428")
					(unit 1)
				)
			)
		)
	)
	(symbol
		(lib_id "antmicroCapacitors0402:C_100n_0402")
		(at 53.34 229.87 90)
		(unit 1)
		(exclude_from_sim no)
		(in_bom yes)
		(on_board yes)
		(dnp no)
		(property "Reference" "C283"
			(at 55.372 226.06 90)
			(effects
				(font
					(size 1.27 1.27)
					(thickness 0.15)
				)
				(justify right)
			)
		)
		(property "Value" "C_100n_0402"
			(at 76.2 214.63 0)
			(effects
				(font
					(size 1.27 1.27)
					(thickness 0.15)
				)
				(justify left bottom)
				(hide yes)
			)
		)
		(property "Footprint" "antmicro-footprints:C_0402_1005Metric"
			(at 78.74 214.63 0)
			(effects
				(font
					(size 1.27 1.27)
					(thickness 0.15)
				)
				(justify left bottom)
				(hide yes)
			)
		)
		(property "Datasheet" "https://www.murata.com/products/productdetail?partno=GRM155R61H104KE14%23"
			(at 81.28 214.63 0)
			(effects
				(font
					(size 1.27 1.27)
					(thickness 0.15)
				)
				(justify left bottom)
				(hide yes)
			)
		)
		(property "Description" "SMD Multilayer Ceramic Capacitor, 0.1 µF, 50 V, 0402 [1005 Metric], ± 10%, X5R, GRM Series"
			(at 53.34 229.87 0)
			(effects
				(font
					(size 1.27 1.27)
				)
				(hide yes)
			)
		)
		(property "MPN" "GRM155R61H104KE14D"
			(at 83.82 214.63 0)
			(effects
				(font
					(size 1.27 1.27)
					(thickness 0.15)
				)
				(justify left bottom)
				(hide yes)
			)
		)
		(property "Val" "100n"
			(at 55.372 228.6 90)
			(effects
				(font
					(size 1.27 1.27)
					(thickness 0.15)
				)
				(justify right)
			)
		)
		(property "Voltage" "50V"
			(at 63.5 214.63 0)
			(effects
				(font
					(size 1.27 1.27)
					(thickness 0.15)
				)
				(justify left bottom)
				(hide yes)
			)
		)
		(property "Dielectric" "X5R"
			(at 66.04 214.63 0)
			(effects
				(font
					(size 1.27 1.27)
					(thickness 0.15)
				)
				(justify left bottom)
				(hide yes)
			)
		)
		(property "Manufacturer" "Murata"
			(at 68.58 214.63 0)
			(effects
				(font
					(size 1.27 1.27)
					(thickness 0.15)
				)
				(justify left bottom)
				(hide yes)
			)
		)
		(property "License" "Apache-2.0"
			(at 71.12 214.63 0)
			(effects
				(font
					(size 1.27 1.27)
					(thickness 0.15)
				)
				(justify left bottom)
				(hide yes)
			)
		)
		(property "Author" "Antmicro"
			(at 73.66 214.63 0)
			(effects
				(font
					(size 1.27 1.27)
					(thickness 0.15)
				)
				(justify left bottom)
				(hide yes)
			)
		)
		(pin "2"
		)
		(pin "1"
		)
		(instances
			(project "OCuLink to 10GbE adapter"
				(path ""
					(reference "C71")
					(unit 1)
				)
			)
			(project "thunderbolt-to-10gbe-adapter"
				(path ""
					(reference "C283")
					(unit 1)
				)
			)
		)
	)
	(symbol
		(lib_id "antmicroResistors0402:R_150R_0402")
		(at 142.24 233.68 90)
		(unit 1)
		(exclude_from_sim no)
		(in_bom yes)
		(on_board yes)
		(dnp no)
		(property "Reference" "R193"
			(at 143.51 229.87 90)
			(effects
				(font
					(size 1.27 1.27)
					(thickness 0.15)
				)
				(justify right)
			)
		)
		(property "Value" "R_150R_0402"
			(at 154.94 213.36 0)
			(effects
				(font
					(size 1.27 1.27)
					(thickness 0.15)
				)
				(justify left bottom)
				(hide yes)
			)
		)
		(property "Footprint" "antmicro-footprints:R_0402_1005Metric"
			(at 157.48 213.36 0)
			(effects
				(font
					(size 1.27 1.27)
					(thickness 0.15)
				)
				(justify left bottom)
				(hide yes)
			)
		)
		(property "Datasheet" "https://www.bourns.com/docs/product-datasheets/cr.pdf"
			(at 160.02 213.36 0)
			(effects
				(font
					(size 1.27 1.27)
					(thickness 0.15)
				)
				(justify left bottom)
				(hide yes)
			)
		)
		(property "Description" "SMD Chip Resistor, 150 ohm, ± 1%, 62.5 mW, 0402 [1005 Metric], Thick Film, General Purpose"
			(at 142.24 233.68 0)
			(effects
				(font
					(size 1.27 1.27)
				)
				(hide yes)
			)
		)
		(property "MPN" "CR0402-FX-1500GLF"
			(at 162.56 213.36 0)
			(effects
				(font
					(size 1.27 1.27)
					(thickness 0.15)
				)
				(justify left bottom)
				(hide yes)
			)
		)
		(property "Manufacturer" "Bourns"
			(at 165.1 213.36 0)
			(effects
				(font
					(size 1.27 1.27)
					(thickness 0.15)
				)
				(justify left bottom)
				(hide yes)
			)
		)
		(property "License" "Apache-2.0"
			(at 167.64 213.36 0)
			(effects
				(font
					(size 1.27 1.27)
					(thickness 0.15)
				)
				(justify left bottom)
				(hide yes)
			)
		)
		(property "Author" "Antmicro"
			(at 170.18 213.36 0)
			(effects
				(font
					(size 1.27 1.27)
					(thickness 0.15)
				)
				(justify left bottom)
				(hide yes)
			)
		)
		(property "Val" "150R"
			(at 143.51 232.41 90)
			(effects
				(font
					(size 1.27 1.27)
					(thickness 0.15)
				)
				(justify right)
			)
		)
		(property "Tolerance" "1%"
			(at 152.4 213.36 0)
			(effects
				(font
					(size 1.27 1.27)
				)
				(justify left bottom)
				(hide yes)
			)
		)
		(pin "2"
		)
		(pin "1"
		)
		(instances
			(project "OCuLink to 10GbE adapter"
				(path ""
					(reference "R46")
					(unit 1)
				)
			)
			(project "thunderbolt-to-10gbe-adapter"
				(path ""
					(reference "R193")
					(unit 1)
				)
			)
		)
	)
	(symbol
		(lib_id "antmicroCapacitors0402:C_100n_0402")
		(at 168.91 223.52 180)
		(unit 1)
		(exclude_from_sim no)
		(in_bom yes)
		(on_board yes)
		(dnp no)
		(property "Reference" "C287"
			(at 164.592 222.25 0)
			(effects
				(font
					(size 1.27 1.27)
					(thickness 0.15)
				)
				(justify left)
			)
		)
		(property "Value" "C_100n_0402"
			(at 153.67 200.66 0)
			(effects
				(font
					(size 1.27 1.27)
					(thickness 0.15)
				)
				(justify left bottom)
				(hide yes)
			)
		)
		(property "Footprint" "antmicro-footprints:C_0402_1005Metric"
			(at 153.67 198.12 0)
			(effects
				(font
					(size 1.27 1.27)
					(thickness 0.15)
				)
				(justify left bottom)
				(hide yes)
			)
		)
		(property "Datasheet" "https://www.murata.com/products/productdetail?partno=GRM155R61H104KE14%23"
			(at 153.67 195.58 0)
			(effects
				(font
					(size 1.27 1.27)
					(thickness 0.15)
				)
				(justify left bottom)
				(hide yes)
			)
		)
		(property "Description" "SMD Multilayer Ceramic Capacitor, 0.1 µF, 50 V, 0402 [1005 Metric], ± 10%, X5R, GRM Series"
			(at 168.91 223.52 0)
			(effects
				(font
					(size 1.27 1.27)
				)
				(hide yes)
			)
		)
		(property "MPN" "GRM155R61H104KE14D"
			(at 153.67 193.04 0)
			(effects
				(font
					(size 1.27 1.27)
					(thickness 0.15)
				)
				(justify left bottom)
				(hide yes)
			)
		)
		(property "Val" "100n"
			(at 167.894 222.25 0)
			(effects
				(font
					(size 1.27 1.27)
					(thickness 0.15)
				)
				(justify right)
			)
		)
		(property "Voltage" "50V"
			(at 153.67 213.36 0)
			(effects
				(font
					(size 1.27 1.27)
					(thickness 0.15)
				)
				(justify left bottom)
				(hide yes)
			)
		)
		(property "Dielectric" "X5R"
			(at 153.67 210.82 0)
			(effects
				(font
					(size 1.27 1.27)
					(thickness 0.15)
				)
				(justify left bottom)
				(hide yes)
			)
		)
		(property "Manufacturer" "Murata"
			(at 153.67 208.28 0)
			(effects
				(font
					(size 1.27 1.27)
					(thickness 0.15)
				)
				(justify left bottom)
				(hide yes)
			)
		)
		(property "License" "Apache-2.0"
			(at 153.67 205.74 0)
			(effects
				(font
					(size 1.27 1.27)
					(thickness 0.15)
				)
				(justify left bottom)
				(hide yes)
			)
		)
		(property "Author" "Antmicro"
			(at 153.67 203.2 0)
			(effects
				(font
					(size 1.27 1.27)
					(thickness 0.15)
				)
				(justify left bottom)
				(hide yes)
			)
		)
		(pin "2"
		)
		(pin "1"
		)
		(instances
			(project "OCuLink to 10GbE adapter"
				(path ""
					(reference "C68")
					(unit 1)
				)
			)
			(project "thunderbolt-to-10gbe-adapter"
				(path ""
					(reference "C287")
					(unit 1)
				)
			)
		)
	)
	(symbol
		(lib_id "antmicroCapacitors0402:C_10p_25V_0402")
		(at 93.98 177.8 90)
		(unit 1)
		(exclude_from_sim no)
		(in_bom yes)
		(on_board yes)
		(dnp no)
		(property "Reference" "C284"
			(at 94.615 173.355 90)
			(effects
				(font
					(size 1.27 1.27)
					(thickness 0.15)
				)
				(justify right)
			)
		)
		(property "Value" "C_10p_25V_0402"
			(at 104.14 157.48 0)
			(effects
				(font
					(size 1.27 1.27)
					(thickness 0.15)
				)
				(justify left bottom)
				(hide yes)
			)
		)
		(property "Footprint" "antmicro-footprints:C_0402_1005Metric"
			(at 106.68 157.48 0)
			(effects
				(font
					(size 1.27 1.27)
					(thickness 0.15)
				)
				(justify left bottom)
				(hide yes)
			)
		)
		(property "Datasheet" "https://spicat.kyocera-avx.com/product/mlcc/chartview/04023A100FAT2A/"
			(at 109.22 157.48 0)
			(effects
				(font
					(size 1.27 1.27)
					(thickness 0.15)
				)
				(justify left bottom)
				(hide yes)
			)
		)
		(property "Description" "Multilayer Ceramic Capacitors MLCC - SMD/SMT 25V 10pF C0G 0402 1%"
			(at 127 157.48 0)
			(effects
				(font
					(size 1.27 1.27)
				)
				(justify left bottom)
				(hide yes)
			)
		)
		(property "MPN" "04023A100FAT2A"
			(at 111.76 157.48 0)
			(effects
				(font
					(size 1.27 1.27)
					(thickness 0.15)
				)
				(justify left bottom)
				(hide yes)
			)
		)
		(property "Manufacturer" "KYOCERA AVX"
			(at 114.3 157.48 0)
			(effects
				(font
					(size 1.27 1.27)
					(thickness 0.15)
				)
				(justify left bottom)
				(hide yes)
			)
		)
		(property "License" "Apache-2.0"
			(at 116.84 157.48 0)
			(effects
				(font
					(size 1.27 1.27)
					(thickness 0.15)
				)
				(justify left bottom)
				(hide yes)
			)
		)
		(property "Author" "Antmicro"
			(at 119.38 157.48 0)
			(effects
				(font
					(size 1.27 1.27)
					(thickness 0.15)
				)
				(justify left bottom)
				(hide yes)
			)
		)
		(property "Val" "10p"
			(at 94.615 177.165 90)
			(effects
				(font
					(size 1.27 1.27)
					(thickness 0.15)
				)
				(justify right)
			)
		)
		(property "Voltage" "25V"
			(at 121.92 157.48 0)
			(effects
				(font
					(size 1.27 1.27)
				)
				(justify left bottom)
				(hide yes)
			)
		)
		(property "Dielectric" "C0G"
			(at 124.46 157.48 0)
			(effects
				(font
					(size 1.27 1.27)
				)
				(justify left bottom)
				(hide yes)
			)
		)
		(pin "1"
		)
		(pin "2"
		)
		(instances
			(project "thunderbolt-to-10gbe-adapter"
				(path ""
					(reference "C284")
					(unit 1)
				)
			)
		)
	)
	(symbol
		(lib_id "antmicroResistors0402:R_0R_0402")
		(at 153.67 203.2 0)
		(unit 1)
		(exclude_from_sim no)
		(in_bom yes)
		(on_board yes)
		(dnp no)
		(property "Reference" "R198"
			(at 153.67 201.93 0)
			(effects
				(font
					(size 1.27 1.27)
					(thickness 0.15)
				)
				(justify right)
			)
		)
		(property "Value" "R_0R_0402"
			(at 173.99 215.9 0)
			(effects
				(font
					(size 1.27 1.27)
					(thickness 0.15)
				)
				(justify left bottom)
				(hide yes)
			)
		)
		(property "Footprint" "antmicro-footprints:R_0402_1005Metric"
			(at 173.99 218.44 0)
			(effects
				(font
					(size 1.27 1.27)
					(thickness 0.15)
				)
				(justify left bottom)
				(hide yes)
			)
		)
		(property "Datasheet" "https://industrial.panasonic.com/cdbs/www-data/pdf/RDA0000/AOA0000C301.pdf"
			(at 173.99 220.98 0)
			(effects
				(font
					(size 1.27 1.27)
					(thickness 0.15)
				)
				(justify left bottom)
				(hide yes)
			)
		)
		(property "Description" "SMD Chip Resistor, Jumper, 0 ohm, 100 mW, 0402 [1005 Metric], Thick Film, General Purpose"
			(at 153.67 203.2 0)
			(effects
				(font
					(size 1.27 1.27)
				)
				(hide yes)
			)
		)
		(property "MPN" "ERJ2GE0R00X"
			(at 173.99 223.52 0)
			(effects
				(font
					(size 1.27 1.27)
					(thickness 0.15)
				)
				(justify left bottom)
				(hide yes)
			)
		)
		(property "Manufacturer" "Panasonic"
			(at 173.99 226.06 0)
			(effects
				(font
					(size 1.27 1.27)
					(thickness 0.15)
				)
				(justify left bottom)
				(hide yes)
			)
		)
		(property "License" "Apache-2.0"
			(at 173.99 228.6 0)
			(effects
				(font
					(size 1.27 1.27)
					(thickness 0.15)
				)
				(justify left bottom)
				(hide yes)
			)
		)
		(property "Author" "Antmicro"
			(at 173.99 231.14 0)
			(effects
				(font
					(size 1.27 1.27)
					(thickness 0.15)
				)
				(justify left bottom)
				(hide yes)
			)
		)
		(property "Val" "0R"
			(at 158.75 201.93 0)
			(effects
				(font
					(size 1.27 1.27)
					(thickness 0.15)
				)
				(justify left)
			)
		)
		(property "Tolerance" "~"
			(at 173.99 213.36 0)
			(effects
				(font
					(size 1.27 1.27)
				)
				(justify left bottom)
				(hide yes)
			)
		)
		(property "Current" "1A"
			(at 173.99 233.68 0)
			(effects
				(font
					(size 1.27 1.27)
					(thickness 0.15)
				)
				(justify left bottom)
				(hide yes)
			)
		)
		(pin "1"
		)
		(pin "2"
		)
		(instances
			(project "OCuLink to 10GbE adapter"
				(path ""
					(reference "R71")
					(unit 1)
				)
			)
			(project "thunderbolt-to-10gbe-adapter"
				(path ""
					(reference "R198")
					(unit 1)
				)
			)
		)
	)
	(symbol
		(lib_id "antmicroResistors0402:R_3k3_0402")
		(at 175.26 165.1 90)
		(unit 1)
		(exclude_from_sim no)
		(in_bom yes)
		(on_board yes)
		(dnp no)
		(property "Reference" "R201"
			(at 176.784 161.29 90)
			(effects
				(font
					(size 1.27 1.27)
					(thickness 0.15)
				)
				(justify right)
			)
		)
		(property "Value" "R_3k3_0402"
			(at 187.96 144.78 0)
			(effects
				(font
					(size 1.27 1.27)
					(thickness 0.15)
				)
				(justify left bottom)
				(hide yes)
			)
		)
		(property "Footprint" "antmicro-footprints:R_0402_1005Metric"
			(at 190.5 144.78 0)
			(effects
				(font
					(size 1.27 1.27)
					(thickness 0.15)
				)
				(justify left bottom)
				(hide yes)
			)
		)
		(property "Datasheet" "https://www.bourns.com/docs/product-datasheets/cr.pdf"
			(at 193.04 144.78 0)
			(effects
				(font
					(size 1.27 1.27)
					(thickness 0.15)
				)
				(justify left bottom)
				(hide yes)
			)
		)
		(property "Description" "SMD Chip Resistor, 3.3 kohm, ± 1%, 63 mW, 0402 [1005 Metric], Thick Film, General Purpose"
			(at 175.26 165.1 0)
			(effects
				(font
					(size 1.27 1.27)
				)
				(hide yes)
			)
		)
		(property "MPN" "CR0402-FX-3301GLF"
			(at 195.58 144.78 0)
			(effects
				(font
					(size 1.27 1.27)
					(thickness 0.15)
				)
				(justify left bottom)
				(hide yes)
			)
		)
		(property "Manufacturer" "Bourns"
			(at 198.12 144.78 0)
			(effects
				(font
					(size 1.27 1.27)
					(thickness 0.15)
				)
				(justify left bottom)
				(hide yes)
			)
		)
		(property "License" "Apache-2.0"
			(at 200.66 144.78 0)
			(effects
				(font
					(size 1.27 1.27)
					(thickness 0.15)
				)
				(justify left bottom)
				(hide yes)
			)
		)
		(property "Author" "Antmicro"
			(at 203.2 144.78 0)
			(effects
				(font
					(size 1.27 1.27)
					(thickness 0.15)
				)
				(justify left bottom)
				(hide yes)
			)
		)
		(property "Val" "3k3"
			(at 176.784 163.83 90)
			(effects
				(font
					(size 1.27 1.27)
					(thickness 0.15)
				)
				(justify right)
			)
		)
		(property "Tolerance" "1%"
			(at 185.42 144.78 0)
			(effects
				(font
					(size 1.27 1.27)
				)
				(justify left bottom)
				(hide yes)
			)
		)
		(pin "2"
		)
		(pin "1"
		)
		(instances
			(project "OCuLink to 10GbE adapter"
				(path ""
					(reference "R66")
					(unit 1)
				)
			)
			(project "thunderbolt-to-10gbe-adapter"
				(path ""
					(reference "R201")
					(unit 1)
				)
			)
		)
	)
	(symbol
		(lib_id "antmicropower:GND")
		(at 78.74 236.22 0)
		(unit 1)
		(exclude_from_sim no)
		(in_bom yes)
		(on_board yes)
		(dnp no)
		(property "Reference" "#PWR0416"
			(at 87.63 238.76 0)
			(effects
				(font
					(size 1.27 1.27)
					(thickness 0.15)
				)
				(justify left bottom)
				(hide yes)
			)
		)
		(property "Value" "GND"
			(at 78.74 240.03 0)
			(effects
				(font
					(size 1.27 1.27)
					(thickness 0.15)
				)
			)
		)
		(property "Footprint" ""
			(at 87.63 243.84 0)
			(effects
				(font
					(size 1.27 1.27)
					(thickness 0.15)
				)
				(justify left bottom)
				(hide yes)
			)
		)
		(property "Datasheet" ""
			(at 87.63 248.92 0)
			(effects
				(font
					(size 1.27 1.27)
					(thickness 0.15)
				)
				(justify left bottom)
				(hide yes)
			)
		)
		(property "Description" ""
			(at 78.74 236.22 0)
			(effects
				(font
					(size 1.27 1.27)
				)
				(hide yes)
			)
		)
		(property "Author" "Antmicro"
			(at 87.63 243.84 0)
			(effects
				(font
					(size 1.27 1.27)
					(thickness 0.15)
				)
				(justify left bottom)
				(hide yes)
			)
		)
		(property "License" "Apache-2.0"
			(at 87.63 246.38 0)
			(effects
				(font
					(size 1.27 1.27)
					(thickness 0.15)
				)
				(justify left bottom)
				(hide yes)
			)
		)
		(pin "1"
		)
		(instances
			(project "OCuLink to 10GbE adapter"
				(path ""
					(reference "#PWR092")
					(unit 1)
				)
			)
			(project "thunderbolt-to-10gbe-adapter"
				(path ""
					(reference "#PWR0416")
					(unit 1)
				)
			)
		)
	)
	(symbol
		(lib_id "antmicroResistors0402:R_8k2_0402")
		(at 175.26 241.3 90)
		(unit 1)
		(exclude_from_sim no)
		(in_bom yes)
		(on_board yes)
		(dnp no)
		(property "Reference" "R202"
			(at 176.784 237.49 90)
			(effects
				(font
					(size 1.27 1.27)
					(thickness 0.15)
				)
				(justify right)
			)
		)
		(property "Value" "R_8k2_0402"
			(at 187.96 220.98 0)
			(effects
				(font
					(size 1.27 1.27)
					(thickness 0.15)
				)
				(justify left bottom)
				(hide yes)
			)
		)
		(property "Footprint" "antmicro-footprints:R_0402_1005Metric"
			(at 190.5 220.98 0)
			(effects
				(font
					(size 1.27 1.27)
					(thickness 0.15)
				)
				(justify left bottom)
				(hide yes)
			)
		)
		(property "Datasheet" "https://www.bourns.com/docs/product-datasheets/cr.pdf"
			(at 193.04 220.98 0)
			(effects
				(font
					(size 1.27 1.27)
					(thickness 0.15)
				)
				(justify left bottom)
				(hide yes)
			)
		)
		(property "Description" "SMD Chip Resistor"
			(at 175.26 241.3 0)
			(effects
				(font
					(size 1.27 1.27)
				)
				(hide yes)
			)
		)
		(property "MPN" "CR0402-FX-8201GLF"
			(at 195.58 220.98 0)
			(effects
				(font
					(size 1.27 1.27)
					(thickness 0.15)
				)
				(justify left bottom)
				(hide yes)
			)
		)
		(property "Manufacturer" "Bourns"
			(at 198.12 220.98 0)
			(effects
				(font
					(size 1.27 1.27)
					(thickness 0.15)
				)
				(justify left bottom)
				(hide yes)
			)
		)
		(property "License" "Apache-2.0"
			(at 200.66 220.98 0)
			(effects
				(font
					(size 1.27 1.27)
					(thickness 0.15)
				)
				(justify left bottom)
				(hide yes)
			)
		)
		(property "Author" "Antmicro"
			(at 203.2 220.98 0)
			(effects
				(font
					(size 1.27 1.27)
					(thickness 0.15)
				)
				(justify left bottom)
				(hide yes)
			)
		)
		(property "Val" "8k2"
			(at 176.784 240.03 90)
			(effects
				(font
					(size 1.27 1.27)
					(thickness 0.15)
				)
				(justify right)
			)
		)
		(property "Tolerance" "1%"
			(at 185.42 220.98 0)
			(effects
				(font
					(size 1.27 1.27)
				)
				(justify left bottom)
				(hide yes)
			)
		)
		(pin "2"
		)
		(pin "1"
		)
		(instances
			(project ""
				(path ""
					(reference "R76")
					(unit 1)
				)
			)
			(project "thunderbolt-to-10gbe-adapter"
				(path ""
					(reference "R202")
					(unit 1)
				)
			)
		)
	)
	(symbol
		(lib_id "antmicropower:GND")
		(at 93.98 180.34 0)
		(unit 1)
		(exclude_from_sim no)
		(in_bom yes)
		(on_board yes)
		(dnp no)
		(property "Reference" "#PWR0417"
			(at 102.87 182.88 0)
			(effects
				(font
					(size 1.27 1.27)
					(thickness 0.15)
				)
				(justify left bottom)
				(hide yes)
			)
		)
		(property "Value" "GND"
			(at 93.98 184.15 0)
			(effects
				(font
					(size 1.27 1.27)
					(thickness 0.15)
				)
			)
		)
		(property "Footprint" ""
			(at 102.87 187.96 0)
			(effects
				(font
					(size 1.27 1.27)
					(thickness 0.15)
				)
				(justify left bottom)
				(hide yes)
			)
		)
		(property "Datasheet" ""
			(at 102.87 193.04 0)
			(effects
				(font
					(size 1.27 1.27)
					(thickness 0.15)
				)
				(justify left bottom)
				(hide yes)
			)
		)
		(property "Description" ""
			(at 93.98 180.34 0)
			(effects
				(font
					(size 1.27 1.27)
				)
				(hide yes)
			)
		)
		(property "Author" "Antmicro"
			(at 102.87 187.96 0)
			(effects
				(font
					(size 1.27 1.27)
					(thickness 0.15)
				)
				(justify left bottom)
				(hide yes)
			)
		)
		(property "License" "Apache-2.0"
			(at 102.87 190.5 0)
			(effects
				(font
					(size 1.27 1.27)
					(thickness 0.15)
				)
				(justify left bottom)
				(hide yes)
			)
		)
		(pin "1"
		)
		(instances
			(project "thunderbolt-to-10gbe-adapter"
				(path ""
					(reference "#PWR0417")
					(unit 1)
				)
			)
		)
	)
	(symbol
		(lib_id "antmicropower:+3V3")
		(at 175.26 154.94 0)
		(unit 1)
		(exclude_from_sim no)
		(in_bom yes)
		(on_board yes)
		(dnp no)
		(property "Reference" "#PWR0421"
			(at 190.5 154.94 0)
			(effects
				(font
					(size 1.27 1.27)
					(thickness 0.15)
				)
				(justify left bottom)
				(hide yes)
			)
		)
		(property "Value" "+3V3"
			(at 175.26 151.13 0)
			(effects
				(font
					(size 1.27 1.27)
					(thickness 0.15)
				)
			)
		)
		(property "Footprint" ""
			(at 190.5 162.56 0)
			(effects
				(font
					(size 1.27 1.27)
					(thickness 0.15)
				)
				(justify left bottom)
				(hide yes)
			)
		)
		(property "Datasheet" ""
			(at 190.5 165.1 0)
			(effects
				(font
					(size 1.27 1.27)
					(thickness 0.15)
				)
				(justify left bottom)
				(hide yes)
			)
		)
		(property "Description" ""
			(at 175.26 154.94 0)
			(effects
				(font
					(size 1.27 1.27)
				)
				(hide yes)
			)
		)
		(property "Author" "Antmicro"
			(at 190.5 157.48 0)
			(effects
				(font
					(size 1.27 1.27)
					(thickness 0.15)
				)
				(justify left bottom)
				(hide yes)
			)
		)
		(property "License" "Apache-2.0"
			(at 190.5 160.02 0)
			(effects
				(font
					(size 1.27 1.27)
					(thickness 0.15)
				)
				(justify left bottom)
				(hide yes)
			)
		)
		(pin "1"
		)
		(instances
			(project "OCuLink to 10GbE adapter"
				(path ""
					(reference "#PWR0252")
					(unit 1)
				)
			)
			(project "thunderbolt-to-10gbe-adapter"
				(path ""
					(reference "#PWR0421")
					(unit 1)
				)
			)
		)
	)
	(symbol
		(lib_id "antmicroResistors0402:R_3k3_0402")
		(at 152.4 165.1 90)
		(unit 1)
		(exclude_from_sim no)
		(in_bom yes)
		(on_board yes)
		(dnp no)
		(property "Reference" "R195"
			(at 153.924 161.29 90)
			(effects
				(font
					(size 1.27 1.27)
					(thickness 0.15)
				)
				(justify right)
			)
		)
		(property "Value" "R_3k3_0402"
			(at 165.1 144.78 0)
			(effects
				(font
					(size 1.27 1.27)
					(thickness 0.15)
				)
				(justify left bottom)
				(hide yes)
			)
		)
		(property "Footprint" "antmicro-footprints:R_0402_1005Metric"
			(at 167.64 144.78 0)
			(effects
				(font
					(size 1.27 1.27)
					(thickness 0.15)
				)
				(justify left bottom)
				(hide yes)
			)
		)
		(property "Datasheet" "https://www.bourns.com/docs/product-datasheets/cr.pdf"
			(at 170.18 144.78 0)
			(effects
				(font
					(size 1.27 1.27)
					(thickness 0.15)
				)
				(justify left bottom)
				(hide yes)
			)
		)
		(property "Description" "SMD Chip Resistor, 3.3 kohm, ± 1%, 63 mW, 0402 [1005 Metric], Thick Film, General Purpose"
			(at 152.4 165.1 0)
			(effects
				(font
					(size 1.27 1.27)
				)
				(hide yes)
			)
		)
		(property "MPN" "CR0402-FX-3301GLF"
			(at 172.72 144.78 0)
			(effects
				(font
					(size 1.27 1.27)
					(thickness 0.15)
				)
				(justify left bottom)
				(hide yes)
			)
		)
		(property "Manufacturer" "Bourns"
			(at 175.26 144.78 0)
			(effects
				(font
					(size 1.27 1.27)
					(thickness 0.15)
				)
				(justify left bottom)
				(hide yes)
			)
		)
		(property "License" "Apache-2.0"
			(at 177.8 144.78 0)
			(effects
				(font
					(size 1.27 1.27)
					(thickness 0.15)
				)
				(justify left bottom)
				(hide yes)
			)
		)
		(property "Author" "Antmicro"
			(at 180.34 144.78 0)
			(effects
				(font
					(size 1.27 1.27)
					(thickness 0.15)
				)
				(justify left bottom)
				(hide yes)
			)
		)
		(property "Val" "3k3"
			(at 153.924 163.83 90)
			(effects
				(font
					(size 1.27 1.27)
					(thickness 0.15)
				)
				(justify right)
			)
		)
		(property "Tolerance" "1%"
			(at 162.56 144.78 0)
			(effects
				(font
					(size 1.27 1.27)
				)
				(justify left bottom)
				(hide yes)
			)
		)
		(pin "2"
		)
		(pin "1"
		)
		(instances
			(project "OCuLink to 10GbE adapter"
				(path ""
					(reference "R63")
					(unit 1)
				)
			)
			(project "thunderbolt-to-10gbe-adapter"
				(path ""
					(reference "R195")
					(unit 1)
				)
			)
		)
	)
	(symbol
		(lib_id "antmicroResistors0402:R_3k3_0402")
		(at 167.64 165.1 90)
		(unit 1)
		(exclude_from_sim no)
		(in_bom yes)
		(on_board yes)
		(dnp no)
		(property "Reference" "R200"
			(at 169.164 161.29 90)
			(effects
				(font
					(size 1.27 1.27)
					(thickness 0.15)
				)
				(justify right)
			)
		)
		(property "Value" "R_3k3_0402"
			(at 180.34 144.78 0)
			(effects
				(font
					(size 1.27 1.27)
					(thickness 0.15)
				)
				(justify left bottom)
				(hide yes)
			)
		)
		(property "Footprint" "antmicro-footprints:R_0402_1005Metric"
			(at 182.88 144.78 0)
			(effects
				(font
					(size 1.27 1.27)
					(thickness 0.15)
				)
				(justify left bottom)
				(hide yes)
			)
		)
		(property "Datasheet" "https://www.bourns.com/docs/product-datasheets/cr.pdf"
			(at 185.42 144.78 0)
			(effects
				(font
					(size 1.27 1.27)
					(thickness 0.15)
				)
				(justify left bottom)
				(hide yes)
			)
		)
		(property "Description" "SMD Chip Resistor, 3.3 kohm, ± 1%, 63 mW, 0402 [1005 Metric], Thick Film, General Purpose"
			(at 167.64 165.1 0)
			(effects
				(font
					(size 1.27 1.27)
				)
				(hide yes)
			)
		)
		(property "MPN" "CR0402-FX-3301GLF"
			(at 187.96 144.78 0)
			(effects
				(font
					(size 1.27 1.27)
					(thickness 0.15)
				)
				(justify left bottom)
				(hide yes)
			)
		)
		(property "Manufacturer" "Bourns"
			(at 190.5 144.78 0)
			(effects
				(font
					(size 1.27 1.27)
					(thickness 0.15)
				)
				(justify left bottom)
				(hide yes)
			)
		)
		(property "License" "Apache-2.0"
			(at 193.04 144.78 0)
			(effects
				(font
					(size 1.27 1.27)
					(thickness 0.15)
				)
				(justify left bottom)
				(hide yes)
			)
		)
		(property "Author" "Antmicro"
			(at 195.58 144.78 0)
			(effects
				(font
					(size 1.27 1.27)
					(thickness 0.15)
				)
				(justify left bottom)
				(hide yes)
			)
		)
		(property "Val" "3k3"
			(at 169.164 163.83 90)
			(effects
				(font
					(size 1.27 1.27)
					(thickness 0.15)
				)
				(justify right)
			)
		)
		(property "Tolerance" "1%"
			(at 177.8 144.78 0)
			(effects
				(font
					(size 1.27 1.27)
				)
				(justify left bottom)
				(hide yes)
			)
		)
		(pin "2"
		)
		(pin "1"
		)
		(instances
			(project "OCuLink to 10GbE adapter"
				(path ""
					(reference "R65")
					(unit 1)
				)
			)
			(project "thunderbolt-to-10gbe-adapter"
				(path ""
					(reference "R200")
					(unit 1)
				)
			)
		)
	)
	(symbol
		(lib_id "antmicropower:GND")
		(at 261.62 241.3 0)
		(unit 1)
		(exclude_from_sim no)
		(in_bom yes)
		(on_board yes)
		(dnp no)
		(property "Reference" "#PWR0427"
			(at 270.51 243.84 0)
			(effects
				(font
					(size 1.27 1.27)
					(thickness 0.15)
				)
				(justify left bottom)
				(hide yes)
			)
		)
		(property "Value" "GND"
			(at 261.62 245.11 0)
			(effects
				(font
					(size 1.27 1.27)
					(thickness 0.15)
				)
			)
		)
		(property "Footprint" ""
			(at 270.51 248.92 0)
			(effects
				(font
					(size 1.27 1.27)
					(thickness 0.15)
				)
				(justify left bottom)
				(hide yes)
			)
		)
		(property "Datasheet" ""
			(at 270.51 254 0)
			(effects
				(font
					(size 1.27 1.27)
					(thickness 0.15)
				)
				(justify left bottom)
				(hide yes)
			)
		)
		(property "Description" ""
			(at 261.62 241.3 0)
			(effects
				(font
					(size 1.27 1.27)
				)
				(hide yes)
			)
		)
		(property "Author" "Antmicro"
			(at 270.51 248.92 0)
			(effects
				(font
					(size 1.27 1.27)
					(thickness 0.15)
				)
				(justify left bottom)
				(hide yes)
			)
		)
		(property "License" "Apache-2.0"
			(at 270.51 251.46 0)
			(effects
				(font
					(size 1.27 1.27)
					(thickness 0.15)
				)
				(justify left bottom)
				(hide yes)
			)
		)
		(pin "1"
		)
		(instances
			(project "OCuLink to 10GbE adapter"
				(path ""
					(reference "#PWR0256")
					(unit 1)
				)
			)
			(project "thunderbolt-to-10gbe-adapter"
				(path ""
					(reference "#PWR0427")
					(unit 1)
				)
			)
		)
	)
	(symbol
		(lib_id "antmicroResistors0402:R_10k_0402")
		(at 64.77 226.06 0)
		(unit 1)
		(exclude_from_sim no)
		(in_bom yes)
		(on_board yes)
		(dnp no)
		(property "Reference" "R184"
			(at 67.31 223.774 0)
			(effects
				(font
					(size 1.27 1.27)
					(thickness 0.15)
				)
			)
		)
		(property "Value" "R_10k_0402"
			(at 85.09 238.76 0)
			(effects
				(font
					(size 1.27 1.27)
					(thickness 0.15)
				)
				(justify left bottom)
				(hide yes)
			)
		)
		(property "Footprint" "antmicro-footprints:R_0402_1005Metric"
			(at 85.09 241.3 0)
			(effects
				(font
					(size 1.27 1.27)
					(thickness 0.15)
				)
				(justify left bottom)
				(hide yes)
			)
		)
		(property "Datasheet" "https://www.bourns.com/docs/product-datasheets/cr.pdf"
			(at 85.09 243.84 0)
			(effects
				(font
					(size 1.27 1.27)
					(thickness 0.15)
				)
				(justify left bottom)
				(hide yes)
			)
		)
		(property "Description" "SMD Chip Resistor, 10 kohm, ± 1%, 62.5 mW, 0402 [1005 Metric], Thick Film, General Purpose"
			(at 64.77 226.06 0)
			(effects
				(font
					(size 1.27 1.27)
				)
				(hide yes)
			)
		)
		(property "MPN" "CR0402-FX-1002GLF"
			(at 85.09 246.38 0)
			(effects
				(font
					(size 1.27 1.27)
					(thickness 0.15)
				)
				(justify left bottom)
				(hide yes)
			)
		)
		(property "Manufacturer" "Bourns"
			(at 85.09 248.92 0)
			(effects
				(font
					(size 1.27 1.27)
					(thickness 0.15)
				)
				(justify left bottom)
				(hide yes)
			)
		)
		(property "License" "Apache-2.0"
			(at 85.09 251.46 0)
			(effects
				(font
					(size 1.27 1.27)
					(thickness 0.15)
				)
				(justify left bottom)
				(hide yes)
			)
		)
		(property "Author" "Antmicro"
			(at 85.09 254 0)
			(effects
				(font
					(size 1.27 1.27)
					(thickness 0.15)
				)
				(justify left bottom)
				(hide yes)
			)
		)
		(property "Val" "10k"
			(at 67.31 228.346 0)
			(effects
				(font
					(size 1.27 1.27)
					(thickness 0.15)
				)
			)
		)
		(property "Tolerance" "1%"
			(at 85.09 236.22 0)
			(effects
				(font
					(size 1.27 1.27)
				)
				(justify left bottom)
				(hide yes)
			)
		)
		(pin "1"
		)
		(pin "2"
		)
		(instances
			(project "OCuLink to 10GbE adapter"
				(path ""
					(reference "R43")
					(unit 1)
				)
			)
			(project "thunderbolt-to-10gbe-adapter"
				(path ""
					(reference "R184")
					(unit 1)
				)
			)
		)
	)
	(symbol
		(lib_id "antmicroResistors0402:R_0R_0402")
		(at 153.67 200.66 0)
		(unit 1)
		(exclude_from_sim no)
		(in_bom yes)
		(on_board yes)
		(dnp no)
		(property "Reference" "R197"
			(at 153.67 199.39 0)
			(effects
				(font
					(size 1.27 1.27)
					(thickness 0.15)
				)
				(justify right)
			)
		)
		(property "Value" "R_0R_0402"
			(at 173.99 213.36 0)
			(effects
				(font
					(size 1.27 1.27)
					(thickness 0.15)
				)
				(justify left bottom)
				(hide yes)
			)
		)
		(property "Footprint" "antmicro-footprints:R_0402_1005Metric"
			(at 173.99 215.9 0)
			(effects
				(font
					(size 1.27 1.27)
					(thickness 0.15)
				)
				(justify left bottom)
				(hide yes)
			)
		)
		(property "Datasheet" "https://industrial.panasonic.com/cdbs/www-data/pdf/RDA0000/AOA0000C301.pdf"
			(at 173.99 218.44 0)
			(effects
				(font
					(size 1.27 1.27)
					(thickness 0.15)
				)
				(justify left bottom)
				(hide yes)
			)
		)
		(property "Description" "SMD Chip Resistor, Jumper, 0 ohm, 100 mW, 0402 [1005 Metric], Thick Film, General Purpose"
			(at 153.67 200.66 0)
			(effects
				(font
					(size 1.27 1.27)
				)
				(hide yes)
			)
		)
		(property "MPN" "ERJ2GE0R00X"
			(at 173.99 220.98 0)
			(effects
				(font
					(size 1.27 1.27)
					(thickness 0.15)
				)
				(justify left bottom)
				(hide yes)
			)
		)
		(property "Manufacturer" "Panasonic"
			(at 173.99 223.52 0)
			(effects
				(font
					(size 1.27 1.27)
					(thickness 0.15)
				)
				(justify left bottom)
				(hide yes)
			)
		)
		(property "License" "Apache-2.0"
			(at 173.99 226.06 0)
			(effects
				(font
					(size 1.27 1.27)
					(thickness 0.15)
				)
				(justify left bottom)
				(hide yes)
			)
		)
		(property "Author" "Antmicro"
			(at 173.99 228.6 0)
			(effects
				(font
					(size 1.27 1.27)
					(thickness 0.15)
				)
				(justify left bottom)
				(hide yes)
			)
		)
		(property "Val" "0R"
			(at 158.75 199.39 0)
			(effects
				(font
					(size 1.27 1.27)
					(thickness 0.15)
				)
				(justify left)
			)
		)
		(property "Tolerance" "~"
			(at 173.99 210.82 0)
			(effects
				(font
					(size 1.27 1.27)
				)
				(justify left bottom)
				(hide yes)
			)
		)
		(property "Current" "1A"
			(at 173.99 231.14 0)
			(effects
				(font
					(size 1.27 1.27)
					(thickness 0.15)
				)
				(justify left bottom)
				(hide yes)
			)
		)
		(pin "1"
		)
		(pin "2"
		)
		(instances
			(project "OCuLink to 10GbE adapter"
				(path ""
					(reference "R70")
					(unit 1)
				)
			)
			(project "thunderbolt-to-10gbe-adapter"
				(path ""
					(reference "R197")
					(unit 1)
				)
			)
		)
	)
	(symbol
		(lib_id "antmicroCapacitors0402:C_10p_25V_0402")
		(at 99.06 177.8 90)
		(unit 1)
		(exclude_from_sim no)
		(in_bom yes)
		(on_board yes)
		(dnp no)
		(property "Reference" "C285"
			(at 99.695 173.355 90)
			(effects
				(font
					(size 1.27 1.27)
					(thickness 0.15)
				)
				(justify right)
			)
		)
		(property "Value" "C_10p_25V_0402"
			(at 109.22 157.48 0)
			(effects
				(font
					(size 1.27 1.27)
					(thickness 0.15)
				)
				(justify left bottom)
				(hide yes)
			)
		)
		(property "Footprint" "antmicro-footprints:C_0402_1005Metric"
			(at 111.76 157.48 0)
			(effects
				(font
					(size 1.27 1.27)
					(thickness 0.15)
				)
				(justify left bottom)
				(hide yes)
			)
		)
		(property "Datasheet" "https://spicat.kyocera-avx.com/product/mlcc/chartview/04023A100FAT2A/"
			(at 114.3 157.48 0)
			(effects
				(font
					(size 1.27 1.27)
					(thickness 0.15)
				)
				(justify left bottom)
				(hide yes)
			)
		)
		(property "Description" "Multilayer Ceramic Capacitors MLCC - SMD/SMT 25V 10pF C0G 0402 1%"
			(at 132.08 157.48 0)
			(effects
				(font
					(size 1.27 1.27)
				)
				(justify left bottom)
				(hide yes)
			)
		)
		(property "MPN" "04023A100FAT2A"
			(at 116.84 157.48 0)
			(effects
				(font
					(size 1.27 1.27)
					(thickness 0.15)
				)
				(justify left bottom)
				(hide yes)
			)
		)
		(property "Manufacturer" "KYOCERA AVX"
			(at 119.38 157.48 0)
			(effects
				(font
					(size 1.27 1.27)
					(thickness 0.15)
				)
				(justify left bottom)
				(hide yes)
			)
		)
		(property "License" "Apache-2.0"
			(at 121.92 157.48 0)
			(effects
				(font
					(size 1.27 1.27)
					(thickness 0.15)
				)
				(justify left bottom)
				(hide yes)
			)
		)
		(property "Author" "Antmicro"
			(at 124.46 157.48 0)
			(effects
				(font
					(size 1.27 1.27)
					(thickness 0.15)
				)
				(justify left bottom)
				(hide yes)
			)
		)
		(property "Val" "10p"
			(at 99.695 177.165 90)
			(effects
				(font
					(size 1.27 1.27)
					(thickness 0.15)
				)
				(justify right)
			)
		)
		(property "Voltage" "25V"
			(at 127 157.48 0)
			(effects
				(font
					(size 1.27 1.27)
				)
				(justify left bottom)
				(hide yes)
			)
		)
		(property "Dielectric" "C0G"
			(at 129.54 157.48 0)
			(effects
				(font
					(size 1.27 1.27)
				)
				(justify left bottom)
				(hide yes)
			)
		)
		(pin "1"
		)
		(pin "2"
		)
		(instances
			(project "thunderbolt-to-10gbe-adapter"
				(path ""
					(reference "C285")
					(unit 1)
				)
			)
		)
	)
	(symbol
		(lib_id "antmicroResistors0402:R_150R_0402")
		(at 133.35 233.68 90)
		(unit 1)
		(exclude_from_sim no)
		(in_bom yes)
		(on_board yes)
		(dnp no)
		(property "Reference" "R191"
			(at 134.62 229.87 90)
			(effects
				(font
					(size 1.27 1.27)
					(thickness 0.15)
				)
				(justify right)
			)
		)
		(property "Value" "R_150R_0402"
			(at 146.05 213.36 0)
			(effects
				(font
					(size 1.27 1.27)
					(thickness 0.15)
				)
				(justify left bottom)
				(hide yes)
			)
		)
		(property "Footprint" "antmicro-footprints:R_0402_1005Metric"
			(at 148.59 213.36 0)
			(effects
				(font
					(size 1.27 1.27)
					(thickness 0.15)
				)
				(justify left bottom)
				(hide yes)
			)
		)
		(property "Datasheet" "https://www.bourns.com/docs/product-datasheets/cr.pdf"
			(at 151.13 213.36 0)
			(effects
				(font
					(size 1.27 1.27)
					(thickness 0.15)
				)
				(justify left bottom)
				(hide yes)
			)
		)
		(property "Description" "SMD Chip Resistor, 150 ohm, ± 1%, 62.5 mW, 0402 [1005 Metric], Thick Film, General Purpose"
			(at 133.35 233.68 0)
			(effects
				(font
					(size 1.27 1.27)
				)
				(hide yes)
			)
		)
		(property "MPN" "CR0402-FX-1500GLF"
			(at 153.67 213.36 0)
			(effects
				(font
					(size 1.27 1.27)
					(thickness 0.15)
				)
				(justify left bottom)
				(hide yes)
			)
		)
		(property "Manufacturer" "Bourns"
			(at 156.21 213.36 0)
			(effects
				(font
					(size 1.27 1.27)
					(thickness 0.15)
				)
				(justify left bottom)
				(hide yes)
			)
		)
		(property "License" "Apache-2.0"
			(at 158.75 213.36 0)
			(effects
				(font
					(size 1.27 1.27)
					(thickness 0.15)
				)
				(justify left bottom)
				(hide yes)
			)
		)
		(property "Author" "Antmicro"
			(at 161.29 213.36 0)
			(effects
				(font
					(size 1.27 1.27)
					(thickness 0.15)
				)
				(justify left bottom)
				(hide yes)
			)
		)
		(property "Val" "150R"
			(at 134.62 232.41 90)
			(effects
				(font
					(size 1.27 1.27)
					(thickness 0.15)
				)
				(justify right)
			)
		)
		(property "Tolerance" "1%"
			(at 143.51 213.36 0)
			(effects
				(font
					(size 1.27 1.27)
				)
				(justify left bottom)
				(hide yes)
			)
		)
		(pin "2"
		)
		(pin "1"
		)
		(instances
			(project "OCuLink to 10GbE adapter"
				(path ""
					(reference "R45")
					(unit 1)
				)
			)
			(project "thunderbolt-to-10gbe-adapter"
				(path ""
					(reference "R191")
					(unit 1)
				)
			)
		)
	)
	(symbol
		(lib_id "antmicropower:+3V3")
		(at 175.26 233.68 0)
		(unit 1)
		(exclude_from_sim no)
		(in_bom yes)
		(on_board yes)
		(dnp no)
		(property "Reference" "#PWR0422"
			(at 190.5 233.68 0)
			(effects
				(font
					(size 1.27 1.27)
					(thickness 0.15)
				)
				(justify left bottom)
				(hide yes)
			)
		)
		(property "Value" "+3V3"
			(at 175.26 229.87 0)
			(effects
				(font
					(size 1.27 1.27)
					(thickness 0.15)
				)
			)
		)
		(property "Footprint" ""
			(at 190.5 241.3 0)
			(effects
				(font
					(size 1.27 1.27)
					(thickness 0.15)
				)
				(justify left bottom)
				(hide yes)
			)
		)
		(property "Datasheet" ""
			(at 190.5 243.84 0)
			(effects
				(font
					(size 1.27 1.27)
					(thickness 0.15)
				)
				(justify left bottom)
				(hide yes)
			)
		)
		(property "Description" ""
			(at 175.26 233.68 0)
			(effects
				(font
					(size 1.27 1.27)
				)
				(hide yes)
			)
		)
		(property "Author" "Antmicro"
			(at 190.5 236.22 0)
			(effects
				(font
					(size 1.27 1.27)
					(thickness 0.15)
				)
				(justify left bottom)
				(hide yes)
			)
		)
		(property "License" "Apache-2.0"
			(at 190.5 238.76 0)
			(effects
				(font
					(size 1.27 1.27)
					(thickness 0.15)
				)
				(justify left bottom)
				(hide yes)
			)
		)
		(pin "1"
		)
		(instances
			(project "OCuLink to 10GbE adapter"
				(path ""
					(reference "#PWR0254")
					(unit 1)
				)
			)
			(project "thunderbolt-to-10gbe-adapter"
				(path ""
					(reference "#PWR0422")
					(unit 1)
				)
			)
		)
	)
	(symbol
		(lib_id "antmicropower:GND")
		(at 255.27 121.92 0)
		(unit 1)
		(exclude_from_sim no)
		(in_bom yes)
		(on_board yes)
		(dnp no)
		(property "Reference" "#PWR0425"
			(at 264.16 124.46 0)
			(effects
				(font
					(size 1.27 1.27)
					(thickness 0.15)
				)
				(justify left bottom)
				(hide yes)
			)
		)
		(property "Value" "GND"
			(at 255.27 125.73 0)
			(effects
				(font
					(size 1.27 1.27)
					(thickness 0.15)
				)
			)
		)
		(property "Footprint" ""
			(at 264.16 129.54 0)
			(effects
				(font
					(size 1.27 1.27)
					(thickness 0.15)
				)
				(justify left bottom)
				(hide yes)
			)
		)
		(property "Datasheet" ""
			(at 264.16 134.62 0)
			(effects
				(font
					(size 1.27 1.27)
					(thickness 0.15)
				)
				(justify left bottom)
				(hide yes)
			)
		)
		(property "Description" ""
			(at 255.27 121.92 0)
			(effects
				(font
					(size 1.27 1.27)
				)
				(hide yes)
			)
		)
		(property "Author" "Antmicro"
			(at 264.16 129.54 0)
			(effects
				(font
					(size 1.27 1.27)
					(thickness 0.15)
				)
				(justify left bottom)
				(hide yes)
			)
		)
		(property "License" "Apache-2.0"
			(at 264.16 132.08 0)
			(effects
				(font
					(size 1.27 1.27)
					(thickness 0.15)
				)
				(justify left bottom)
				(hide yes)
			)
		)
		(pin "1"
		)
		(instances
			(project "OCuLink to 10GbE adapter"
				(path ""
					(reference "#PWR0250")
					(unit 1)
				)
			)
			(project "thunderbolt-to-10gbe-adapter"
				(path ""
					(reference "#PWR0425")
					(unit 1)
				)
			)
		)
	)
	(symbol
		(lib_id "antmicropower:GND")
		(at 99.06 180.34 0)
		(unit 1)
		(exclude_from_sim no)
		(in_bom yes)
		(on_board yes)
		(dnp no)
		(property "Reference" "#PWR0418"
			(at 107.95 182.88 0)
			(effects
				(font
					(size 1.27 1.27)
					(thickness 0.15)
				)
				(justify left bottom)
				(hide yes)
			)
		)
		(property "Value" "GND"
			(at 99.06 184.15 0)
			(effects
				(font
					(size 1.27 1.27)
					(thickness 0.15)
				)
			)
		)
		(property "Footprint" ""
			(at 107.95 187.96 0)
			(effects
				(font
					(size 1.27 1.27)
					(thickness 0.15)
				)
				(justify left bottom)
				(hide yes)
			)
		)
		(property "Datasheet" ""
			(at 107.95 193.04 0)
			(effects
				(font
					(size 1.27 1.27)
					(thickness 0.15)
				)
				(justify left bottom)
				(hide yes)
			)
		)
		(property "Description" ""
			(at 99.06 180.34 0)
			(effects
				(font
					(size 1.27 1.27)
				)
				(hide yes)
			)
		)
		(property "Author" "Antmicro"
			(at 107.95 187.96 0)
			(effects
				(font
					(size 1.27 1.27)
					(thickness 0.15)
				)
				(justify left bottom)
				(hide yes)
			)
		)
		(property "License" "Apache-2.0"
			(at 107.95 190.5 0)
			(effects
				(font
					(size 1.27 1.27)
					(thickness 0.15)
				)
				(justify left bottom)
				(hide yes)
			)
		)
		(pin "1"
		)
		(instances
			(project "thunderbolt-to-10gbe-adapter"
				(path ""
					(reference "#PWR0418")
					(unit 1)
				)
			)
		)
	)
	(symbol
		(lib_id "antmicroCapacitors0402:C_100n_0402")
		(at 38.1 229.87 90)
		(unit 1)
		(exclude_from_sim no)
		(in_bom yes)
		(on_board yes)
		(dnp no)
		(property "Reference" "C282"
			(at 40.132 226.06 90)
			(effects
				(font
					(size 1.27 1.27)
					(thickness 0.15)
				)
				(justify right)
			)
		)
		(property "Value" "C_100n_0402"
			(at 60.96 214.63 0)
			(effects
				(font
					(size 1.27 1.27)
					(thickness 0.15)
				)
				(justify left bottom)
				(hide yes)
			)
		)
		(property "Footprint" "antmicro-footprints:C_0402_1005Metric"
			(at 63.5 214.63 0)
			(effects
				(font
					(size 1.27 1.27)
					(thickness 0.15)
				)
				(justify left bottom)
				(hide yes)
			)
		)
		(property "Datasheet" "https://www.murata.com/products/productdetail?partno=GRM155R61H104KE14%23"
			(at 66.04 214.63 0)
			(effects
				(font
					(size 1.27 1.27)
					(thickness 0.15)
				)
				(justify left bottom)
				(hide yes)
			)
		)
		(property "Description" "SMD Multilayer Ceramic Capacitor, 0.1 µF, 50 V, 0402 [1005 Metric], ± 10%, X5R, GRM Series"
			(at 38.1 229.87 0)
			(effects
				(font
					(size 1.27 1.27)
				)
				(hide yes)
			)
		)
		(property "MPN" "GRM155R61H104KE14D"
			(at 68.58 214.63 0)
			(effects
				(font
					(size 1.27 1.27)
					(thickness 0.15)
				)
				(justify left bottom)
				(hide yes)
			)
		)
		(property "Val" "100n"
			(at 40.132 228.6 90)
			(effects
				(font
					(size 1.27 1.27)
					(thickness 0.15)
				)
				(justify right)
			)
		)
		(property "Voltage" "50V"
			(at 48.26 214.63 0)
			(effects
				(font
					(size 1.27 1.27)
					(thickness 0.15)
				)
				(justify left bottom)
				(hide yes)
			)
		)
		(property "Dielectric" "X5R"
			(at 50.8 214.63 0)
			(effects
				(font
					(size 1.27 1.27)
					(thickness 0.15)
				)
				(justify left bottom)
				(hide yes)
			)
		)
		(property "Manufacturer" "Murata"
			(at 53.34 214.63 0)
			(effects
				(font
					(size 1.27 1.27)
					(thickness 0.15)
				)
				(justify left bottom)
				(hide yes)
			)
		)
		(property "License" "Apache-2.0"
			(at 55.88 214.63 0)
			(effects
				(font
					(size 1.27 1.27)
					(thickness 0.15)
				)
				(justify left bottom)
				(hide yes)
			)
		)
		(property "Author" "Antmicro"
			(at 58.42 214.63 0)
			(effects
				(font
					(size 1.27 1.27)
					(thickness 0.15)
				)
				(justify left bottom)
				(hide yes)
			)
		)
		(pin "2"
		)
		(pin "1"
		)
		(instances
			(project "OCuLink to 10GbE adapter"
				(path ""
					(reference "C70")
					(unit 1)
				)
			)
			(project "thunderbolt-to-10gbe-adapter"
				(path ""
					(reference "C282")
					(unit 1)
				)
			)
		)
	)
	(symbol
		(lib_id "antmicroResistors0402:R_10R_0402")
		(at 105.41 170.18 0)
		(unit 1)
		(exclude_from_sim no)
		(in_bom yes)
		(on_board yes)
		(dnp no)
		(property "Reference" "R186"
			(at 105.41 168.91 0)
			(effects
				(font
					(size 1.27 1.27)
					(thickness 0.15)
				)
				(justify right)
			)
		)
		(property "Value" "R_10R_0402"
			(at 125.73 182.88 0)
			(effects
				(font
					(size 1.27 1.27)
					(thickness 0.15)
				)
				(justify left bottom)
				(hide yes)
			)
		)
		(property "Footprint" "antmicro-footprints:R_0402_1005Metric"
			(at 125.73 185.42 0)
			(effects
				(font
					(size 1.27 1.27)
					(thickness 0.15)
				)
				(justify left bottom)
				(hide yes)
			)
		)
		(property "Datasheet" "https://www.bourns.com/docs/product-datasheets/cr.pdf"
			(at 125.73 187.96 0)
			(effects
				(font
					(size 1.27 1.27)
					(thickness 0.15)
				)
				(justify left bottom)
				(hide yes)
			)
		)
		(property "Description" "SMD Chip Resistor, 10 ohm, ± 1%, 62.5 mW, 0402 [1005 Metric], Thick Film, General Purpose"
			(at 105.41 170.18 0)
			(effects
				(font
					(size 1.27 1.27)
				)
				(hide yes)
			)
		)
		(property "MPN" "CR0402-FX-10R0GLF"
			(at 125.73 190.5 0)
			(effects
				(font
					(size 1.27 1.27)
					(thickness 0.15)
				)
				(justify left bottom)
				(hide yes)
			)
		)
		(property "Manufacturer" "Bourns"
			(at 125.73 193.04 0)
			(effects
				(font
					(size 1.27 1.27)
					(thickness 0.15)
				)
				(justify left bottom)
				(hide yes)
			)
		)
		(property "License" "Apache-2.0"
			(at 125.73 195.58 0)
			(effects
				(font
					(size 1.27 1.27)
					(thickness 0.15)
				)
				(justify left bottom)
				(hide yes)
			)
		)
		(property "Author" "Antmicro"
			(at 125.73 198.12 0)
			(effects
				(font
					(size 1.27 1.27)
					(thickness 0.15)
				)
				(justify left bottom)
				(hide yes)
			)
		)
		(property "Val" "10R"
			(at 110.49 168.91 0)
			(effects
				(font
					(size 1.27 1.27)
					(thickness 0.15)
				)
				(justify left)
			)
		)
		(property "Tolerance" "1%"
			(at 125.73 180.34 0)
			(effects
				(font
					(size 1.27 1.27)
				)
				(justify left bottom)
				(hide yes)
			)
		)
		(pin "2"
		)
		(pin "1"
		)
		(instances
			(project "OCuLink to 10GbE adapter"
				(path ""
					(reference "R68")
					(unit 1)
				)
			)
			(project "thunderbolt-to-10gbe-adapter"
				(path ""
					(reference "R186")
					(unit 1)
				)
			)
		)
	)
	(symbol
		(lib_id "antmicroResistors0402:R_22R_0402")
		(at 121.92 223.52 0)
		(unit 1)
		(exclude_from_sim no)
		(in_bom yes)
		(on_board yes)
		(dnp no)
		(property "Reference" "R188"
			(at 121.92 222.504 0)
			(effects
				(font
					(size 1.27 1.27)
					(thickness 0.15)
				)
				(justify right)
			)
		)
		(property "Value" "R_22R_0402"
			(at 142.24 236.22 0)
			(effects
				(font
					(size 1.27 1.27)
					(thickness 0.15)
				)
				(justify left bottom)
				(hide yes)
			)
		)
		(property "Footprint" "antmicro-footprints:R_0402_1005Metric"
			(at 142.24 238.76 0)
			(effects
				(font
					(size 1.27 1.27)
					(thickness 0.15)
				)
				(justify left bottom)
				(hide yes)
			)
		)
		(property "Datasheet" "https://www.bourns.com/docs/product-datasheets/cr.pdf"
			(at 142.24 241.3 0)
			(effects
				(font
					(size 1.27 1.27)
					(thickness 0.15)
				)
				(justify left bottom)
				(hide yes)
			)
		)
		(property "Description" "SMD Chip Resistor, 22 ohm, ± 1%, 62.5 mW, 0402 [1005 Metric], Thick Film, General Purpose"
			(at 121.92 223.52 0)
			(effects
				(font
					(size 1.27 1.27)
				)
				(hide yes)
			)
		)
		(property "MPN" "CR0402-FX-22R0GLF"
			(at 142.24 243.84 0)
			(effects
				(font
					(size 1.27 1.27)
					(thickness 0.15)
				)
				(justify left bottom)
				(hide yes)
			)
		)
		(property "Manufacturer" "Bourns"
			(at 142.24 246.38 0)
			(effects
				(font
					(size 1.27 1.27)
					(thickness 0.15)
				)
				(justify left bottom)
				(hide yes)
			)
		)
		(property "License" "Apache-2.0"
			(at 142.24 248.92 0)
			(effects
				(font
					(size 1.27 1.27)
					(thickness 0.15)
				)
				(justify left bottom)
				(hide yes)
			)
		)
		(property "Author" "Antmicro"
			(at 142.24 251.46 0)
			(effects
				(font
					(size 1.27 1.27)
					(thickness 0.15)
				)
				(justify left bottom)
				(hide yes)
			)
		)
		(property "Val" "22R"
			(at 127.254 222.504 0)
			(effects
				(font
					(size 1.27 1.27)
					(thickness 0.15)
				)
				(justify left)
			)
		)
		(property "Tolerance" "1%"
			(at 142.24 233.68 0)
			(effects
				(font
					(size 1.27 1.27)
				)
				(justify left bottom)
				(hide yes)
			)
		)
		(pin "1"
		)
		(pin "2"
		)
		(instances
			(project "OCuLink to 10GbE adapter"
				(path ""
					(reference "R42")
					(unit 1)
				)
			)
			(project "thunderbolt-to-10gbe-adapter"
				(path ""
					(reference "R188")
					(unit 1)
				)
			)
		)
	)
	(symbol
		(lib_id "antmicropower:GND")
		(at 133.35 236.22 0)
		(unit 1)
		(exclude_from_sim no)
		(in_bom yes)
		(on_board yes)
		(dnp no)
		(property "Reference" "#PWR0419"
			(at 142.24 238.76 0)
			(effects
				(font
					(size 1.27 1.27)
					(thickness 0.15)
				)
				(justify left bottom)
				(hide yes)
			)
		)
		(property "Value" "GND"
			(at 133.35 240.03 0)
			(effects
				(font
					(size 1.27 1.27)
					(thickness 0.15)
				)
			)
		)
		(property "Footprint" ""
			(at 142.24 243.84 0)
			(effects
				(font
					(size 1.27 1.27)
					(thickness 0.15)
				)
				(justify left bottom)
				(hide yes)
			)
		)
		(property "Datasheet" ""
			(at 142.24 248.92 0)
			(effects
				(font
					(size 1.27 1.27)
					(thickness 0.15)
				)
				(justify left bottom)
				(hide yes)
			)
		)
		(property "Description" ""
			(at 133.35 236.22 0)
			(effects
				(font
					(size 1.27 1.27)
				)
				(hide yes)
			)
		)
		(property "Author" "Antmicro"
			(at 142.24 243.84 0)
			(effects
				(font
					(size 1.27 1.27)
					(thickness 0.15)
				)
				(justify left bottom)
				(hide yes)
			)
		)
		(property "License" "Apache-2.0"
			(at 142.24 246.38 0)
			(effects
				(font
					(size 1.27 1.27)
					(thickness 0.15)
				)
				(justify left bottom)
				(hide yes)
			)
		)
		(pin "1"
		)
		(instances
			(project "OCuLink to 10GbE adapter"
				(path ""
					(reference "#PWR093")
					(unit 1)
				)
			)
			(project "thunderbolt-to-10gbe-adapter"
				(path ""
					(reference "#PWR0419")
					(unit 1)
				)
			)
		)
	)
	(symbol
		(lib_id "antmicropower:GND")
		(at 175.26 254 0)
		(unit 1)
		(exclude_from_sim no)
		(in_bom yes)
		(on_board yes)
		(dnp no)
		(property "Reference" "#PWR0423"
			(at 184.15 256.54 0)
			(effects
				(font
					(size 1.27 1.27)
					(thickness 0.15)
				)
				(justify left bottom)
				(hide yes)
			)
		)
		(property "Value" "GND"
			(at 175.26 257.81 0)
			(effects
				(font
					(size 1.27 1.27)
					(thickness 0.15)
				)
			)
		)
		(property "Footprint" ""
			(at 184.15 261.62 0)
			(effects
				(font
					(size 1.27 1.27)
					(thickness 0.15)
				)
				(justify left bottom)
				(hide yes)
			)
		)
		(property "Datasheet" ""
			(at 184.15 266.7 0)
			(effects
				(font
					(size 1.27 1.27)
					(thickness 0.15)
				)
				(justify left bottom)
				(hide yes)
			)
		)
		(property "Description" ""
			(at 175.26 254 0)
			(effects
				(font
					(size 1.27 1.27)
				)
				(hide yes)
			)
		)
		(property "Author" "Antmicro"
			(at 184.15 261.62 0)
			(effects
				(font
					(size 1.27 1.27)
					(thickness 0.15)
				)
				(justify left bottom)
				(hide yes)
			)
		)
		(property "License" "Apache-2.0"
			(at 184.15 264.16 0)
			(effects
				(font
					(size 1.27 1.27)
					(thickness 0.15)
				)
				(justify left bottom)
				(hide yes)
			)
		)
		(pin "1"
		)
		(instances
			(project "OCuLink to 10GbE adapter"
				(path ""
					(reference "#PWR0257")
					(unit 1)
				)
			)
			(project "thunderbolt-to-10gbe-adapter"
				(path ""
					(reference "#PWR0423")
					(unit 1)
				)
			)
		)
	)
	(symbol
		(lib_id "antmicroResistors0402:R_6k04_0.1%_0402")
		(at 264.16 119.38 90)
		(unit 1)
		(exclude_from_sim no)
		(in_bom yes)
		(on_board yes)
		(dnp no)
		(property "Reference" "R209"
			(at 265.684 114.3 90)
			(effects
				(font
					(size 1.27 1.27)
					(thickness 0.15)
				)
				(justify right)
			)
		)
		(property "Value" "R_6k04_0.1%_0402"
			(at 276.86 99.06 0)
			(effects
				(font
					(size 1.27 1.27)
					(thickness 0.15)
				)
				(justify left bottom)
				(hide yes)
			)
		)
		(property "Footprint" "antmicro-footprints:R_0402_1005Metric"
			(at 279.4 99.06 0)
			(effects
				(font
					(size 1.27 1.27)
					(thickness 0.15)
				)
				(justify left bottom)
				(hide yes)
			)
		)
		(property "Datasheet" "https://www.vishay.com/docs/28758/tnpw_e3.pdf"
			(at 281.94 99.06 0)
			(effects
				(font
					(size 1.27 1.27)
					(thickness 0.15)
				)
				(justify left bottom)
				(hide yes)
			)
		)
		(property "Description" "SMD Chip Resistor, 6.49 kohm, ± 1%, 62.5 mW, 0402 [1005 Metric], Thick Film, General Purpose"
			(at 264.16 119.38 0)
			(effects
				(font
					(size 1.27 1.27)
				)
				(hide yes)
			)
		)
		(property "MPN" "TNPW04026K04BEED"
			(at 284.48 99.06 0)
			(effects
				(font
					(size 1.27 1.27)
					(thickness 0.15)
				)
				(justify left bottom)
				(hide yes)
			)
		)
		(property "Manufacturer" "Vishay"
			(at 287.02 99.06 0)
			(effects
				(font
					(size 1.27 1.27)
					(thickness 0.15)
				)
				(justify left bottom)
				(hide yes)
			)
		)
		(property "License" "Apache-2.0"
			(at 289.56 99.06 0)
			(effects
				(font
					(size 1.27 1.27)
					(thickness 0.15)
				)
				(justify left bottom)
				(hide yes)
			)
		)
		(property "Author" "Antmicro"
			(at 292.1 99.06 0)
			(effects
				(font
					(size 1.27 1.27)
					(thickness 0.15)
				)
				(justify left bottom)
				(hide yes)
			)
		)
		(property "Val" "6k04"
			(at 265.684 116.84 90)
			(effects
				(font
					(size 1.27 1.27)
					(thickness 0.15)
				)
				(justify right)
			)
		)
		(property "Tolerance" "0.1%"
			(at 265.684 119.3799 90)
			(effects
				(font
					(size 1.27 1.27)
				)
				(justify right)
			)
		)
		(pin "1"
		)
		(pin "2"
		)
		(instances
			(project "OCuLink to 10GbE adapter"
				(path ""
					(reference "R58")
					(unit 1)
				)
			)
			(project "thunderbolt-to-10gbe-adapter"
				(path ""
					(reference "R209")
					(unit 1)
				)
			)
		)
	)
	(symbol
		(lib_id "antmicroFerriteBeadsandChips:FB_330Z_1.5A_Murata-BLM21PG_0805")
		(at 43.18 217.17 0)
		(unit 1)
		(exclude_from_sim no)
		(in_bom yes)
		(on_board yes)
		(dnp no)
		(fields_autoplaced yes)
		(property "Reference" "FB8"
			(at 45.6819 210.82 0)
			(effects
				(font
					(size 1.27 1.27)
					(thickness 0.15)
				)
			)
		)
		(property "Value" "FB_330Z_1.5A_Murata-BLM21PG_0805"
			(at 57.15 219.71 0)
			(effects
				(font
					(size 1.27 1.27)
					(thickness 0.15)
				)
				(justify left bottom)
				(hide yes)
			)
		)
		(property "Footprint" "antmicro-footprints:FB_0805_2012Metric"
			(at 57.15 224.79 0)
			(effects
				(font
					(size 1.27 1.27)
					(thickness 0.15)
				)
				(justify left bottom)
				(hide yes)
			)
		)
		(property "Datasheet" "https://www.murata.com/products/productdata/8796738977822/ENFA0005.pdf?1653276712000"
			(at 57.15 227.33 0)
			(effects
				(font
					(size 1.27 1.27)
					(thickness 0.15)
				)
				(justify left bottom)
				(hide yes)
			)
		)
		(property "Description" "Ferrite Bead, 0805 [2012 Metric], 330 ohm, 1.5 A, BLM21P, 0.07 ohm, ± 25%, DC power line"
			(at 43.18 217.17 0)
			(effects
				(font
					(size 1.27 1.27)
				)
				(hide yes)
			)
		)
		(property "Val" "330Z/1.5A"
			(at 45.6819 213.36 0)
			(effects
				(font
					(size 1.27 1.27)
				)
			)
		)
		(property "MPN" "BLM21PG331SN1D"
			(at 57.15 229.87 0)
			(effects
				(font
					(size 1.27 1.27)
					(thickness 0.15)
				)
				(justify left bottom)
				(hide yes)
			)
		)
		(property "Manufacturer" "Murata"
			(at 57.15 232.41 0)
			(effects
				(font
					(size 1.27 1.27)
					(thickness 0.15)
				)
				(justify left bottom)
				(hide yes)
			)
		)
		(property "Current" ""
			(at 63.5 240.03 0)
			(effects
				(font
					(size 1.27 1.27)
					(thickness 0.15)
				)
				(justify left bottom)
				(hide yes)
			)
		)
		(property "Author" "Antmicro"
			(at 57.15 234.95 0)
			(effects
				(font
					(size 1.27 1.27)
					(thickness 0.15)
				)
				(justify left bottom)
				(hide yes)
			)
		)
		(property "License" "Apache-2.0"
			(at 57.15 237.49 0)
			(effects
				(font
					(size 1.27 1.27)
					(thickness 0.15)
				)
				(justify left bottom)
				(hide yes)
			)
		)
		(pin "1"
		)
		(pin "2"
		)
		(instances
			(project "OCuLink to 10GbE adapter"
				(path ""
					(reference "FB2")
					(unit 1)
				)
			)
			(project "thunderbolt-to-10gbe-adapter"
				(path ""
					(reference "FB8")
					(unit 1)
				)
			)
		)
	)
	(symbol
		(lib_id "antmicroInterfaceControllers:EZX710AT2_S_LMR5")
		(at 193.04 53.34 0)
		(unit 2)
		(exclude_from_sim no)
		(in_bom yes)
		(on_board yes)
		(dnp no)
		(fields_autoplaced yes)
		(property "Reference" "U14"
			(at 213.36 45.72 0)
			(effects
				(font
					(size 1.27 1.27)
					(thickness 0.15)
				)
			)
		)
		(property "Value" "EZX710AT2_S_LMR5"
			(at 269.24 58.42 0)
			(effects
				(font
					(size 1.27 1.27)
					(thickness 0.15)
				)
				(justify left bottom)
				(hide yes)
			)
		)
		(property "Footprint" "antmicro-footprints:FCBGA-503_22x22mm_Layout21x24_P1mm"
			(at 269.24 60.96 0)
			(effects
				(font
					(size 1.27 1.27)
					(thickness 0.15)
				)
				(justify left bottom)
				(hide yes)
			)
		)
		(property "Datasheet" "https://www.google.com/url?sa=t&source=web&rct=j&opi=89978449&url=https://cdrdv2-public.intel.com/596333/596333_X710-TM4_Datasheet_v_2_4.pdf&ved=2ahUKEwiSuv20_sCOAxXVCRAIHdxGO_UQFnoECBEQAQ&usg=AOvVaw1CjGyrGWE8ZvOdw4VBsY6U"
			(at 269.24 63.5 0)
			(effects
				(font
					(size 1.27 1.27)
					(thickness 0.15)
				)
				(justify left bottom)
				(hide yes)
			)
		)
		(property "Description" "Ethernet ICs Intel Ethernet Controller 10 Gigabit X7"
			(at 269.24 66.04 0)
			(effects
				(font
					(size 1.27 1.27)
					(thickness 0.15)
				)
				(justify left bottom)
				(hide yes)
			)
		)
		(property "MPN" "EZX710AT2 S LMR5"
			(at 213.36 48.26 0)
			(effects
				(font
					(size 1.27 1.27)
					(thickness 0.15)
				)
			)
		)
		(property "Manufacturer" "Intel"
			(at 269.24 68.58 0)
			(effects
				(font
					(size 1.27 1.27)
					(thickness 0.15)
				)
				(justify left bottom)
				(hide yes)
			)
		)
		(property "Author" "Antmicro"
			(at 269.24 71.12 0)
			(effects
				(font
					(size 1.27 1.27)
					(thickness 0.15)
				)
				(justify left bottom)
				(hide yes)
			)
		)
		(property "License" "Apache-2.0"
			(at 269.24 73.66 0)
			(effects
				(font
					(size 1.27 1.27)
					(thickness 0.15)
				)
				(justify left bottom)
				(hide yes)
			)
		)
		(pin "E39"
		)
		(pin "AD18"
		)
		(pin "AD2"
		)
		(pin "K32"
		)
		(pin "M32"
		)
		(pin "M30"
		)
		(pin "D8"
		)
		(pin "G23"
		)
		(pin "D4"
		)
		(pin "P16"
		)
		(pin "P18"
		)
		(pin "P20"
		)
		(pin "K40"
		)
		(pin "T20"
		)
		(pin "AC31"
		)
		(pin "E5"
		)
		(pin "AD10"
		)
		(pin "W1"
		)
		(pin "G41"
		)
		(pin "W3"
		)
		(pin "U1"
		)
		(pin "H42"
		)
		(pin "H38"
		)
		(pin "K10"
		)
		(pin "U31"
		)
		(pin "V32"
		)
		(pin "C21"
		)
		(pin "B42"
		)
		(pin "V24"
		)
		(pin "P24"
		)
		(pin "Y16"
		)
		(pin "D14"
		)
		(pin "L25"
		)
		(pin "E13"
		)
		(pin "P26"
		)
		(pin "B6"
		)
		(pin "R41"
		)
		(pin "AB32"
		)
		(pin "AB34"
		)
		(pin "R5"
		)
		(pin "T26"
		)
		(pin "AA19"
		)
		(pin "AA21"
		)
		(pin "L37"
		)
		(pin "H2"
		)
		(pin "F22"
		)
		(pin "E19"
		)
		(pin "A17"
		)
		(pin "G19"
		)
		(pin "G21"
		)
		(pin "H34"
		)
		(pin "H36"
		)
		(pin "A15"
		)
		(pin "A19"
		)
		(pin "R39"
		)
		(pin "W37"
		)
		(pin "W39"
		)
		(pin "Y14"
		)
		(pin "L5"
		)
		(pin "N3"
		)
		(pin "N1"
		)
		(pin "T4"
		)
		(pin "B18"
		)
		(pin "W31"
		)
		(pin "W33"
		)
		(pin "W35"
		)
		(pin "W41"
		)
		(pin "C19"
		)
		(pin "C5"
		)
		(pin "M42"
		)
		(pin "G37"
		)
		(pin "L39"
		)
		(pin "F4"
		)
		(pin "AD20"
		)
		(pin "G7"
		)
		(pin "T40"
		)
		(pin "J9"
		)
		(pin "AB18"
		)
		(pin "AA35"
		)
		(pin "H6"
		)
		(pin "M8"
		)
		(pin "A39"
		)
		(pin "P28"
		)
		(pin "Y30"
		)
		(pin "G5"
		)
		(pin "AD32"
		)
		(pin "AD8"
		)
		(pin "AB28"
		)
		(pin "H18"
		)
		(pin "H20"
		)
		(pin "J15"
		)
		(pin "H16"
		)
		(pin "P22"
		)
		(pin "M6"
		)
		(pin "E9"
		)
		(pin "H24"
		)
		(pin "K34"
		)
		(pin "K36"
		)
		(pin "K26"
		)
		(pin "B36"
		)
		(pin "C3"
		)
		(pin "AD22"
		)
		(pin "AA27"
		)
		(pin "V4"
		)
		(pin "B38"
		)
		(pin "D42"
		)
		(pin "F12"
		)
		(pin "AB16"
		)
		(pin "K8"
		)
		(pin "M10"
		)
		(pin "H14"
		)
		(pin "G13"
		)
		(pin "H30"
		)
		(pin "H32"
		)
		(pin "B24"
		)
		(pin "L23"
		)
		(pin "A33"
		)
		(pin "AC25"
		)
		(pin "AC27"
		)
		(pin "P32"
		)
		(pin "P30"
		)
		(pin "H4"
		)
		(pin "U25"
		)
		(pin "V12"
		)
		(pin "V14"
		)
		(pin "V16"
		)
		(pin "W9"
		)
		(pin "T8"
		)
		(pin "AA39"
		)
		(pin "M4"
		)
		(pin "AD24"
		)
		(pin "AD30"
		)
		(pin "U5"
		)
		(pin "U7"
		)
		(pin "AA41"
		)
		(pin "AA9"
		)
		(pin "E17"
		)
		(pin "V36"
		)
		(pin "T42"
		)
		(pin "U27"
		)
		(pin "F16"
		)
		(pin "A23"
		)
		(pin "Y18"
		)
		(pin "V2"
		)
		(pin "V8"
		)
		(pin "L35"
		)
		(pin "H40"
		)
		(pin "N5"
		)
		(pin "AA31"
		)
		(pin "C11"
		)
		(pin "C13"
		)
		(pin "B12"
		)
		(pin "B16"
		)
		(pin "P8"
		)
		(pin "A35"
		)
		(pin "T24"
		)
		(pin "Y38"
		)
		(pin "AC39"
		)
		(pin "J3"
		)
		(pin "U9"
		)
		(pin "K24"
		)
		(pin "AD40"
		)
		(pin "C1"
		)
		(pin "L13"
		)
		(pin "L15"
		)
		(pin "F8"
		)
		(pin "F6"
		)
		(pin "AA7"
		)
		(pin "W25"
		)
		(pin "V42"
		)
		(pin "N7"
		)
		(pin "R9"
		)
		(pin "Y2"
		)
		(pin "F24"
		)
		(pin "F26"
		)
		(pin "C35"
		)
		(pin "C37"
		)
		(pin "J25"
		)
		(pin "AC21"
		)
		(pin "AC23"
		)
		(pin "P42"
		)
		(pin "E11"
		)
		(pin "Y12"
		)
		(pin "A5"
		)
		(pin "V38"
		)
		(pin "AB12"
		)
		(pin "AB4"
		)
		(pin "AB40"
		)
		(pin "AD42"
		)
		(pin "AD6"
		)
		(pin "D10"
		)
		(pin "D2"
		)
		(pin "R23"
		)
		(pin "Y24"
		)
		(pin "T38"
		)
		(pin "AD14"
		)
		(pin "AC41"
		)
		(pin "AC7"
		)
		(pin "Y10"
		)
		(pin "U13"
		)
		(pin "U15"
		)
		(pin "W17"
		)
		(pin "W19"
		)
		(pin "W27"
		)
		(pin "M2"
		)
		(pin "L17"
		)
		(pin "N11"
		)
		(pin "H12"
		)
		(pin "B14"
		)
		(pin "G27"
		)
		(pin "G29"
		)
		(pin "K6"
		)
		(pin "AB42"
		)
		(pin "M24"
		)
		(pin "E7"
		)
		(pin "AC17"
		)
		(pin "AC19"
		)
		(pin "R31"
		)
		(pin "R29"
		)
		(pin "A31"
		)
		(pin "B22"
		)
		(pin "B32"
		)
		(pin "Y36"
		)
		(pin "Y4"
		)
		(pin "Y40"
		)
		(pin "R35"
		)
		(pin "T10"
		)
		(pin "T12"
		)
		(pin "J1"
		)
		(pin "V6"
		)
		(pin "A13"
		)
		(pin "W21"
		)
		(pin "L19"
		)
		(pin "Y6"
		)
		(pin "Y8"
		)
		(pin "A21"
		)
		(pin "G35"
		)
		(pin "G25"
		)
		(pin "C25"
		)
		(pin "C27"
		)
		(pin "J17"
		)
		(pin "K30"
		)
		(pin "W23"
		)
		(pin "M12"
		)
		(pin "M14"
		)
		(pin "M16"
		)
		(pin "D18"
		)
		(pin "K42"
		)
		(pin "T14"
		)
		(pin "T16"
		)
		(pin "T18"
		)
		(pin "T28"
		)
		(pin "U39"
		)
		(pin "N39"
		)
		(pin "U17"
		)
		(pin "U19"
		)
		(pin "R11"
		)
		(pin "T34"
		)
		(pin "P38"
		)
		(pin "E1"
		)
		(pin "C7"
		)
		(pin "C9"
		)
		(pin "F2"
		)
		(pin "J29"
		)
		(pin "J31"
		)
		(pin "U37"
		)
		(pin "AC9"
		)
		(pin "AD12"
		)
		(pin "P40"
		)
		(pin "K4"
		)
		(pin "N9"
		)
		(pin "M40"
		)
		(pin "E3"
		)
		(pin "F18"
		)
		(pin "F20"
		)
		(pin "T6"
		)
		(pin "U3"
		)
		(pin "C29"
		)
		(pin "J27"
		)
		(pin "AB26"
		)
		(pin "AB30"
		)
		(pin "AB2"
		)
		(pin "AA1"
		)
		(pin "P2"
		)
		(pin "R1"
		)
		(pin "R33"
		)
		(pin "AC1"
		)
		(pin "AC11"
		)
		(pin "AA5"
		)
		(pin "AC5"
		)
		(pin "AD4"
		)
		(pin "U41"
		)
		(pin "N19"
		)
		(pin "N21"
		)
		(pin "R37"
		)
		(pin "W5"
		)
		(pin "E25"
		)
		(pin "D22"
		)
		(pin "U29"
		)
		(pin "E29"
		)
		(pin "C33"
		)
		(pin "N33"
		)
		(pin "F14"
		)
		(pin "A29"
		)
		(pin "N35"
		)
		(pin "B34"
		)
		(pin "Y20"
		)
		(pin "AC29"
		)
		(pin "AC3"
		)
		(pin "U21"
		)
		(pin "W11"
		)
		(pin "U23"
		)
		(pin "N41"
		)
		(pin "P4"
		)
		(pin "AC35"
		)
		(pin "AD34"
		)
		(pin "AD38"
		)
		(pin "G39"
		)
		(pin "L11"
		)
		(pin "G11"
		)
		(pin "V26"
		)
		(pin "G31"
		)
		(pin "G33"
		)
		(pin "G9"
		)
		(pin "AA23"
		)
		(pin "AA25"
		)
		(pin "G15"
		)
		(pin "K2"
		)
		(pin "U35"
		)
		(pin "U33"
		)
		(pin "J23"
		)
		(pin "R3"
		)
		(pin "B2"
		)
		(pin "B20"
		)
		(pin "P34"
		)
		(pin "E37"
		)
		(pin "E27"
		)
		(pin "J7"
		)
		(pin "H10"
		)
		(pin "J5"
		)
		(pin "AD16"
		)
		(pin "M26"
		)
		(pin "D12"
		)
		(pin "C15"
		)
		(pin "C17"
		)
		(pin "L41"
		)
		(pin "B40"
		)
		(pin "E41"
		)
		(pin "B4"
		)
		(pin "B8"
		)
		(pin "K28"
		)
		(pin "D20"
		)
		(pin "L33"
		)
		(pin "AB24"
		)
		(pin "AC13"
		)
		(pin "AC15"
		)
		(pin "E21"
		)
		(pin "E23"
		)
		(pin "L3"
		)
		(pin "R7"
		)
		(pin "V40"
		)
		(pin "E33"
		)
		(pin "F40"
		)
		(pin "F42"
		)
		(pin "G3"
		)
		(pin "AA15"
		)
		(pin "AA17"
		)
		(pin "M22"
		)
		(pin "W7"
		)
		(pin "AD26"
		)
		(pin "J35"
		)
		(pin "J33"
		)
		(pin "M28"
		)
		(pin "F34"
		)
		(pin "F36"
		)
		(pin "K18"
		)
		(pin "N27"
		)
		(pin "V34"
		)
		(pin "L7"
		)
		(pin "M36"
		)
		(pin "D26"
		)
		(pin "D28"
		)
		(pin "D36"
		)
		(pin "D38"
		)
		(pin "D40"
		)
		(pin "E31"
		)
		(pin "L9"
		)
		(pin "T2"
		)
		(pin "A9"
		)
		(pin "Y26"
		)
		(pin "Y28"
		)
		(pin "Y32"
		)
		(pin "D6"
		)
		(pin "F38"
		)
		(pin "B10"
		)
		(pin "AA11"
		)
		(pin "AA13"
		)
		(pin "R21"
		)
		(pin "U11"
		)
		(pin "AA29"
		)
		(pin "AA3"
		)
		(pin "H26"
		)
		(pin "H28"
		)
		(pin "K12"
		)
		(pin "K14"
		)
		(pin "AB14"
		)
		(pin "AB20"
		)
		(pin "N23"
		)
		(pin "V10"
		)
		(pin "A11"
		)
		(pin "G1"
		)
		(pin "AB36"
		)
		(pin "AB38"
		)
		(pin "P36"
		)
		(pin "M38"
		)
		(pin "D34"
		)
		(pin "B28"
		)
		(pin "C39"
		)
		(pin "C23"
		)
		(pin "J11"
		)
		(pin "AB22"
		)
		(pin "T22"
		)
		(pin "V30"
		)
		(pin "L31"
		)
		(pin "J13"
		)
		(pin "N25"
		)
		(pin "N31"
		)
		(pin "N29"
		)
		(pin "H22"
		)
		(pin "G17"
		)
		(pin "N37"
		)
		(pin "AD36"
		)
		(pin "A27"
		)
		(pin "F10"
		)
		(pin "AD28"
		)
		(pin "L1"
		)
		(pin "E15"
		)
		(pin "A25"
		)
		(pin "L21"
		)
		(pin "N17"
		)
		(pin "A41"
		)
		(pin "L29"
		)
		(pin "A3"
		)
		(pin "A7"
		)
		(pin "T32"
		)
		(pin "T30"
		)
		(pin "P10"
		)
		(pin "P12"
		)
		(pin "P14"
		)
		(pin "J37"
		)
		(pin "M34"
		)
		(pin "R17"
		)
		(pin "R19"
		)
		(pin "N13"
		)
		(pin "N15"
		)
		(pin "R27"
		)
		(pin "J41"
		)
		(pin "D16"
		)
		(pin "D30"
		)
		(pin "E35"
		)
		(pin "B26"
		)
		(pin "F28"
		)
		(pin "F30"
		)
		(pin "F32"
		)
		(pin "J19"
		)
		(pin "J21"
		)
		(pin "K20"
		)
		(pin "M18"
		)
		(pin "M20"
		)
		(pin "W13"
		)
		(pin "W15"
		)
		(pin "AB10"
		)
		(pin "P6"
		)
		(pin "R25"
		)
		(pin "V22"
		)
		(pin "V18"
		)
		(pin "V20"
		)
		(pin "W29"
		)
		(pin "K22"
		)
		(pin "Y22"
		)
		(pin "AC33"
		)
		(pin "AC37"
		)
		(pin "Y42"
		)
		(pin "R13"
		)
		(pin "R15"
		)
		(pin "H8"
		)
		(pin "Y34"
		)
		(pin "T36"
		)
		(pin "V28"
		)
		(pin "AB6"
		)
		(pin "AB8"
		)
		(pin "D32"
		)
		(pin "J39"
		)
		(pin "L27"
		)
		(pin "C31"
		)
		(pin "C41"
		)
		(pin "D24"
		)
		(pin "K16"
		)
		(pin "K38"
		)
		(pin "B30"
		)
		(pin "AA33"
		)
		(pin "AA37"
		)
		(pin "A37"
		)
		(instances
			(project ""
				(path ""
					(reference "U9")
					(unit 2)
				)
			)
			(project "thunderbolt-to-10gbe-adapter"
				(path ""
					(reference "U14")
					(unit 2)
				)
			)
		)
	)
	(symbol
		(lib_id "antmicroResistors0402:R_0R_0402")
		(at 261.62 238.76 90)
		(unit 1)
		(exclude_from_sim no)
		(in_bom yes)
		(on_board yes)
		(dnp no)
		(property "Reference" "R208"
			(at 263.144 234.95 90)
			(effects
				(font
					(size 1.27 1.27)
					(thickness 0.15)
				)
				(justify right)
			)
		)
		(property "Value" "R_0R_0402"
			(at 274.32 218.44 0)
			(effects
				(font
					(size 1.27 1.27)
					(thickness 0.15)
				)
				(justify left bottom)
				(hide yes)
			)
		)
		(property "Footprint" "antmicro-footprints:R_0402_1005Metric"
			(at 276.86 218.44 0)
			(effects
				(font
					(size 1.27 1.27)
					(thickness 0.15)
				)
				(justify left bottom)
				(hide yes)
			)
		)
		(property "Datasheet" "https://industrial.panasonic.com/cdbs/www-data/pdf/RDA0000/AOA0000C301.pdf"
			(at 279.4 218.44 0)
			(effects
				(font
					(size 1.27 1.27)
					(thickness 0.15)
				)
				(justify left bottom)
				(hide yes)
			)
		)
		(property "Description" "SMD Chip Resistor, Jumper, 0 ohm, 100 mW, 0402 [1005 Metric], Thick Film, General Purpose"
			(at 261.62 238.76 0)
			(effects
				(font
					(size 1.27 1.27)
				)
				(hide yes)
			)
		)
		(property "MPN" "ERJ2GE0R00X"
			(at 281.94 218.44 0)
			(effects
				(font
					(size 1.27 1.27)
					(thickness 0.15)
				)
				(justify left bottom)
				(hide yes)
			)
		)
		(property "Manufacturer" "Panasonic"
			(at 284.48 218.44 0)
			(effects
				(font
					(size 1.27 1.27)
					(thickness 0.15)
				)
				(justify left bottom)
				(hide yes)
			)
		)
		(property "License" "Apache-2.0"
			(at 287.02 218.44 0)
			(effects
				(font
					(size 1.27 1.27)
					(thickness 0.15)
				)
				(justify left bottom)
				(hide yes)
			)
		)
		(property "Author" "Antmicro"
			(at 289.56 218.44 0)
			(effects
				(font
					(size 1.27 1.27)
					(thickness 0.15)
				)
				(justify left bottom)
				(hide yes)
			)
		)
		(property "Val" "0R"
			(at 263.144 237.49 90)
			(effects
				(font
					(size 1.27 1.27)
					(thickness 0.15)
				)
				(justify right)
			)
		)
		(property "Tolerance" "~"
			(at 271.78 218.44 0)
			(effects
				(font
					(size 1.27 1.27)
				)
				(justify left bottom)
				(hide yes)
			)
		)
		(property "Current" "1A"
			(at 292.1 218.44 0)
			(effects
				(font
					(size 1.27 1.27)
					(thickness 0.15)
				)
				(justify left bottom)
				(hide yes)
			)
		)
		(pin "1"
		)
		(pin "2"
		)
		(instances
			(project "OCuLink to 10GbE adapter"
				(path ""
					(reference "R75")
					(unit 1)
				)
			)
			(project "thunderbolt-to-10gbe-adapter"
				(path ""
					(reference "R208")
					(unit 1)
				)
			)
		)
	)
	(symbol
		(lib_id "antmicroOscillators:Oscillator_25MHz_511ABA25M0000BAGR")
		(at 81.28 223.52 0)
		(unit 1)
		(exclude_from_sim no)
		(in_bom yes)
		(on_board yes)
		(dnp no)
		(fields_autoplaced yes)
		(property "Reference" "Y4"
			(at 90.805 213.36 0)
			(effects
				(font
					(size 1.27 1.27)
					(thickness 0.15)
				)
			)
		)
		(property "Value" "Oscillator_25MHz_511ABA25M0000BAGR"
			(at 109.855 235.585 0)
			(effects
				(font
					(size 1.27 1.27)
					(thickness 0.15)
				)
				(justify left bottom)
				(hide yes)
			)
		)
		(property "Footprint" "antmicro-footprints:Oscillator_SMD_Skyworks_SI511_5x3.2x1.17mm"
			(at 109.855 238.125 0)
			(effects
				(font
					(size 1.27 1.27)
					(thickness 0.15)
				)
				(justify left bottom)
				(hide yes)
			)
		)
		(property "Datasheet" "https://www.mouser.com/datasheet/2/472/si510_11-2507765.pdf"
			(at 109.855 240.665 0)
			(effects
				(font
					(size 1.27 1.27)
					(thickness 0.15)
				)
				(justify left bottom)
				(hide yes)
			)
		)
		(property "Description" "25 MHz XO (Standard) LVPECL Oscillator 3.3V Enable/Disable 6-SMD, No Lead"
			(at 81.28 223.52 0)
			(effects
				(font
					(size 1.27 1.27)
				)
				(hide yes)
			)
		)
		(property "Manufacturer" "Skyworks Solutions"
			(at 109.855 227.965 0)
			(effects
				(font
					(size 1.27 1.27)
					(thickness 0.15)
				)
				(justify left bottom)
				(hide yes)
			)
		)
		(property "MPN" "511ABA25M0000BAGR"
			(at 90.805 215.9 0)
			(effects
				(font
					(size 1.27 1.27)
					(thickness 0.15)
				)
			)
		)
		(property "Val" "25 MHz"
			(at 90.805 218.44 0)
			(effects
				(font
					(size 1.27 1.27)
					(thickness 0.15)
				)
			)
		)
		(property "Author" "Antmicro"
			(at 109.855 243.205 0)
			(effects
				(font
					(size 1.27 1.27)
					(thickness 0.15)
				)
				(justify left bottom)
				(hide yes)
			)
		)
		(property "License" "Apache-2.0"
			(at 109.855 245.745 0)
			(effects
				(font
					(size 1.27 1.27)
					(thickness 0.15)
				)
				(justify left bottom)
				(hide yes)
			)
		)
		(pin "4"
		)
		(pin "5"
		)
		(pin "6"
		)
		(pin "3"
		)
		(pin "2"
		)
		(pin "1"
		)
		(instances
			(project "OCuLink to 10GbE adapter"
				(path ""
					(reference "Y1")
					(unit 1)
				)
			)
			(project "thunderbolt-to-10gbe-adapter"
				(path ""
					(reference "Y4")
					(unit 1)
				)
			)
		)
	)
	(symbol
		(lib_id "antmicroResistors0402:R_22R_0402")
		(at 121.92 226.06 0)
		(unit 1)
		(exclude_from_sim no)
		(in_bom yes)
		(on_board yes)
		(dnp no)
		(property "Reference" "R189"
			(at 121.92 225.044 0)
			(effects
				(font
					(size 1.27 1.27)
					(thickness 0.15)
				)
				(justify right)
			)
		)
		(property "Value" "R_22R_0402"
			(at 142.24 238.76 0)
			(effects
				(font
					(size 1.27 1.27)
					(thickness 0.15)
				)
				(justify left bottom)
				(hide yes)
			)
		)
		(property "Footprint" "antmicro-footprints:R_0402_1005Metric"
			(at 142.24 241.3 0)
			(effects
				(font
					(size 1.27 1.27)
					(thickness 0.15)
				)
				(justify left bottom)
				(hide yes)
			)
		)
		(property "Datasheet" "https://www.bourns.com/docs/product-datasheets/cr.pdf"
			(at 142.24 243.84 0)
			(effects
				(font
					(size 1.27 1.27)
					(thickness 0.15)
				)
				(justify left bottom)
				(hide yes)
			)
		)
		(property "Description" "SMD Chip Resistor, 22 ohm, ± 1%, 62.5 mW, 0402 [1005 Metric], Thick Film, General Purpose"
			(at 121.92 226.06 0)
			(effects
				(font
					(size 1.27 1.27)
				)
				(hide yes)
			)
		)
		(property "MPN" "CR0402-FX-22R0GLF"
			(at 142.24 246.38 0)
			(effects
				(font
					(size 1.27 1.27)
					(thickness 0.15)
				)
				(justify left bottom)
				(hide yes)
			)
		)
		(property "Manufacturer" "Bourns"
			(at 142.24 248.92 0)
			(effects
				(font
					(size 1.27 1.27)
					(thickness 0.15)
				)
				(justify left bottom)
				(hide yes)
			)
		)
		(property "License" "Apache-2.0"
			(at 142.24 251.46 0)
			(effects
				(font
					(size 1.27 1.27)
					(thickness 0.15)
				)
				(justify left bottom)
				(hide yes)
			)
		)
		(property "Author" "Antmicro"
			(at 142.24 254 0)
			(effects
				(font
					(size 1.27 1.27)
					(thickness 0.15)
				)
				(justify left bottom)
				(hide yes)
			)
		)
		(property "Val" "22R"
			(at 127.254 225.044 0)
			(effects
				(font
					(size 1.27 1.27)
					(thickness 0.15)
				)
				(justify left)
			)
		)
		(property "Tolerance" "1%"
			(at 142.24 236.22 0)
			(effects
				(font
					(size 1.27 1.27)
				)
				(justify left bottom)
				(hide yes)
			)
		)
		(pin "1"
		)
		(pin "2"
		)
		(instances
			(project "OCuLink to 10GbE adapter"
				(path ""
					(reference "R44")
					(unit 1)
				)
			)
			(project "thunderbolt-to-10gbe-adapter"
				(path ""
					(reference "R189")
					(unit 1)
				)
			)
		)
	)
	(symbol
		(lib_id "antmicroResistors0402:R_100R_0402")
		(at 175.26 251.46 90)
		(unit 1)
		(exclude_from_sim no)
		(in_bom yes)
		(on_board yes)
		(dnp yes)
		(property "Reference" "R203"
			(at 176.784 247.65 90)
			(effects
				(font
					(size 1.27 1.27)
					(thickness 0.15)
				)
				(justify right)
			)
		)
		(property "Value" "R_100R_0402"
			(at 187.96 231.14 0)
			(effects
				(font
					(size 1.27 1.27)
					(thickness 0.15)
				)
				(justify left bottom)
				(hide yes)
			)
		)
		(property "Footprint" "antmicro-footprints:R_0402_1005Metric"
			(at 190.5 231.14 0)
			(effects
				(font
					(size 1.27 1.27)
					(thickness 0.15)
				)
				(justify left bottom)
				(hide yes)
			)
		)
		(property "Datasheet" "https://www.bourns.com/docs/product-datasheets/cr.pdf"
			(at 193.04 231.14 0)
			(effects
				(font
					(size 1.27 1.27)
					(thickness 0.15)
				)
				(justify left bottom)
				(hide yes)
			)
		)
		(property "Description" "SMD Chip Resistor, 100 ohm, ± 1%, 62.5 mW, 0402 [1005 Metric], Thick Film, General Purpose"
			(at 175.26 251.46 0)
			(effects
				(font
					(size 1.27 1.27)
				)
				(hide yes)
			)
		)
		(property "MPN" "CR0402-FX-1000GLF"
			(at 195.58 231.14 0)
			(effects
				(font
					(size 1.27 1.27)
					(thickness 0.15)
				)
				(justify left bottom)
				(hide yes)
			)
		)
		(property "Manufacturer" "Bourns"
			(at 198.12 231.14 0)
			(effects
				(font
					(size 1.27 1.27)
					(thickness 0.15)
				)
				(justify left bottom)
				(hide yes)
			)
		)
		(property "License" "Apache-2.0"
			(at 200.66 231.14 0)
			(effects
				(font
					(size 1.27 1.27)
					(thickness 0.15)
				)
				(justify left bottom)
				(hide yes)
			)
		)
		(property "Author" "Antmicro"
			(at 203.2 231.14 0)
			(effects
				(font
					(size 1.27 1.27)
					(thickness 0.15)
				)
				(justify left bottom)
				(hide yes)
			)
		)
		(property "Val" "100R"
			(at 176.784 250.19 90)
			(effects
				(font
					(size 1.27 1.27)
					(thickness 0.15)
				)
				(justify right)
			)
		)
		(property "Tolerance" "1%"
			(at 185.42 231.14 0)
			(effects
				(font
					(size 1.27 1.27)
				)
				(justify left bottom)
				(hide yes)
			)
		)
		(pin "2"
		)
		(pin "1"
		)
		(instances
			(project ""
				(path ""
					(reference "R77")
					(unit 1)
				)
			)
			(project "thunderbolt-to-10gbe-adapter"
				(path ""
					(reference "R203")
					(unit 1)
				)
			)
		)
	)
	(symbol
		(lib_id "antmicropower:+1V8")
		(at 261.62 215.9 0)
		(unit 1)
		(exclude_from_sim no)
		(in_bom yes)
		(on_board yes)
		(dnp no)
		(property "Reference" "#PWR0426"
			(at 276.86 218.44 0)
			(effects
				(font
					(size 1.27 1.27)
					(thickness 0.15)
				)
				(justify left bottom)
				(hide yes)
			)
		)
		(property "Value" "+1V88"
			(at 261.62 212.09 0)
			(effects
				(font
					(size 1.27 1.27)
					(thickness 0.15)
				)
			)
		)
		(property "Footprint" ""
			(at 276.86 223.52 0)
			(effects
				(font
					(size 1.27 1.27)
					(thickness 0.15)
				)
				(justify left bottom)
				(hide yes)
			)
		)
		(property "Datasheet" ""
			(at 276.86 226.06 0)
			(effects
				(font
					(size 1.27 1.27)
					(thickness 0.15)
				)
				(justify left bottom)
				(hide yes)
			)
		)
		(property "Description" ""
			(at 261.62 215.9 0)
			(effects
				(font
					(size 1.27 1.27)
				)
				(hide yes)
			)
		)
		(property "Author" "Antmicro"
			(at 276.86 220.98 0)
			(effects
				(font
					(size 1.27 1.27)
					(thickness 0.15)
				)
				(justify left bottom)
				(hide yes)
			)
		)
		(property "License" "Apache-2.0"
			(at 276.86 223.52 0)
			(effects
				(font
					(size 1.27 1.27)
					(thickness 0.15)
				)
				(justify left bottom)
				(hide yes)
			)
		)
		(pin "1"
		)
		(instances
			(project "OCuLink to 10GbE adapter"
				(path ""
					(reference "#PWR0253")
					(unit 1)
				)
			)
			(project "thunderbolt-to-10gbe-adapter"
				(path ""
					(reference "#PWR0426")
					(unit 1)
				)
			)
		)
	)
	(symbol
		(lib_id "antmicroResistors0402:R_10R_0402")
		(at 105.41 167.64 0)
		(unit 1)
		(exclude_from_sim no)
		(in_bom yes)
		(on_board yes)
		(dnp no)
		(property "Reference" "R185"
			(at 105.41 166.37 0)
			(effects
				(font
					(size 1.27 1.27)
					(thickness 0.15)
				)
				(justify right)
			)
		)
		(property "Value" "R_10R_0402"
			(at 125.73 180.34 0)
			(effects
				(font
					(size 1.27 1.27)
					(thickness 0.15)
				)
				(justify left bottom)
				(hide yes)
			)
		)
		(property "Footprint" "antmicro-footprints:R_0402_1005Metric"
			(at 125.73 182.88 0)
			(effects
				(font
					(size 1.27 1.27)
					(thickness 0.15)
				)
				(justify left bottom)
				(hide yes)
			)
		)
		(property "Datasheet" "https://www.bourns.com/docs/product-datasheets/cr.pdf"
			(at 125.73 185.42 0)
			(effects
				(font
					(size 1.27 1.27)
					(thickness 0.15)
				)
				(justify left bottom)
				(hide yes)
			)
		)
		(property "Description" "SMD Chip Resistor, 10 ohm, ± 1%, 62.5 mW, 0402 [1005 Metric], Thick Film, General Purpose"
			(at 105.41 167.64 0)
			(effects
				(font
					(size 1.27 1.27)
				)
				(hide yes)
			)
		)
		(property "MPN" "CR0402-FX-10R0GLF"
			(at 125.73 187.96 0)
			(effects
				(font
					(size 1.27 1.27)
					(thickness 0.15)
				)
				(justify left bottom)
				(hide yes)
			)
		)
		(property "Manufacturer" "Bourns"
			(at 125.73 190.5 0)
			(effects
				(font
					(size 1.27 1.27)
					(thickness 0.15)
				)
				(justify left bottom)
				(hide yes)
			)
		)
		(property "License" "Apache-2.0"
			(at 125.73 193.04 0)
			(effects
				(font
					(size 1.27 1.27)
					(thickness 0.15)
				)
				(justify left bottom)
				(hide yes)
			)
		)
		(property "Author" "Antmicro"
			(at 125.73 195.58 0)
			(effects
				(font
					(size 1.27 1.27)
					(thickness 0.15)
				)
				(justify left bottom)
				(hide yes)
			)
		)
		(property "Val" "10R"
			(at 110.49 166.37 0)
			(effects
				(font
					(size 1.27 1.27)
					(thickness 0.15)
				)
				(justify left)
			)
		)
		(property "Tolerance" "1%"
			(at 125.73 177.8 0)
			(effects
				(font
					(size 1.27 1.27)
				)
				(justify left bottom)
				(hide yes)
			)
		)
		(pin "2"
		)
		(pin "1"
		)
		(instances
			(project ""
				(path ""
					(reference "R67")
					(unit 1)
				)
			)
			(project "thunderbolt-to-10gbe-adapter"
				(path ""
					(reference "R185")
					(unit 1)
				)
			)
		)
	)
	(symbol
		(lib_id "antmicroResistors0402:R_3k3_0402")
		(at 144.78 165.1 90)
		(unit 1)
		(exclude_from_sim no)
		(in_bom yes)
		(on_board yes)
		(dnp no)
		(property "Reference" "R194"
			(at 146.304 161.29 90)
			(effects
				(font
					(size 1.27 1.27)
					(thickness 0.15)
				)
				(justify right)
			)
		)
		(property "Value" "R_3k3_0402"
			(at 157.48 144.78 0)
			(effects
				(font
					(size 1.27 1.27)
					(thickness 0.15)
				)
				(justify left bottom)
				(hide yes)
			)
		)
		(property "Footprint" "antmicro-footprints:R_0402_1005Metric"
			(at 160.02 144.78 0)
			(effects
				(font
					(size 1.27 1.27)
					(thickness 0.15)
				)
				(justify left bottom)
				(hide yes)
			)
		)
		(property "Datasheet" "https://www.bourns.com/docs/product-datasheets/cr.pdf"
			(at 162.56 144.78 0)
			(effects
				(font
					(size 1.27 1.27)
					(thickness 0.15)
				)
				(justify left bottom)
				(hide yes)
			)
		)
		(property "Description" "SMD Chip Resistor, 3.3 kohm, ± 1%, 63 mW, 0402 [1005 Metric], Thick Film, General Purpose"
			(at 144.78 165.1 0)
			(effects
				(font
					(size 1.27 1.27)
				)
				(hide yes)
			)
		)
		(property "MPN" "CR0402-FX-3301GLF"
			(at 165.1 144.78 0)
			(effects
				(font
					(size 1.27 1.27)
					(thickness 0.15)
				)
				(justify left bottom)
				(hide yes)
			)
		)
		(property "Manufacturer" "Bourns"
			(at 167.64 144.78 0)
			(effects
				(font
					(size 1.27 1.27)
					(thickness 0.15)
				)
				(justify left bottom)
				(hide yes)
			)
		)
		(property "License" "Apache-2.0"
			(at 170.18 144.78 0)
			(effects
				(font
					(size 1.27 1.27)
					(thickness 0.15)
				)
				(justify left bottom)
				(hide yes)
			)
		)
		(property "Author" "Antmicro"
			(at 172.72 144.78 0)
			(effects
				(font
					(size 1.27 1.27)
					(thickness 0.15)
				)
				(justify left bottom)
				(hide yes)
			)
		)
		(property "Val" "3k3"
			(at 146.304 163.83 90)
			(effects
				(font
					(size 1.27 1.27)
					(thickness 0.15)
				)
				(justify right)
			)
		)
		(property "Tolerance" "1%"
			(at 154.94 144.78 0)
			(effects
				(font
					(size 1.27 1.27)
				)
				(justify left bottom)
				(hide yes)
			)
		)
		(pin "2"
		)
		(pin "1"
		)
		(instances
			(project ""
				(path ""
					(reference "R62")
					(unit 1)
				)
			)
			(project "thunderbolt-to-10gbe-adapter"
				(path ""
					(reference "R194")
					(unit 1)
				)
			)
		)
	)
	(symbol
		(lib_id "antmicroResistors0402:R_4k53_0402")
		(at 255.27 119.38 90)
		(unit 1)
		(exclude_from_sim no)
		(in_bom yes)
		(on_board yes)
		(dnp no)
		(property "Reference" "R206"
			(at 256.794 114.3 90)
			(effects
				(font
					(size 1.27 1.27)
					(thickness 0.15)
				)
				(justify right)
			)
		)
		(property "Value" "R_4k53_0402"
			(at 267.97 99.06 0)
			(effects
				(font
					(size 1.27 1.27)
					(thickness 0.15)
				)
				(justify left bottom)
				(hide yes)
			)
		)
		(property "Footprint" "antmicro-footprints:R_0402_1005Metric"
			(at 270.51 99.06 0)
			(effects
				(font
					(size 1.27 1.27)
					(thickness 0.15)
				)
				(justify left bottom)
				(hide yes)
			)
		)
		(property "Datasheet" "https://industrial.panasonic.com/cdbs/www-data/pdf/RDM0000/AOA0000C307.pdf"
			(at 273.05 99.06 0)
			(effects
				(font
					(size 1.27 1.27)
					(thickness 0.15)
				)
				(justify left bottom)
				(hide yes)
			)
		)
		(property "Description" "SMD Chip Resistor, 4.53 kohm, ± 0.1%, 62.5 mW, 0402 [1005 Metric], Automotive AEC-Q200 Thin Film"
			(at 255.27 119.38 0)
			(effects
				(font
					(size 1.27 1.27)
				)
				(hide yes)
			)
		)
		(property "MPN" "ERA-2AEB4531X"
			(at 275.59 99.06 0)
			(effects
				(font
					(size 1.27 1.27)
					(thickness 0.15)
				)
				(justify left bottom)
				(hide yes)
			)
		)
		(property "Manufacturer" "Panasonic"
			(at 278.13 99.06 0)
			(effects
				(font
					(size 1.27 1.27)
					(thickness 0.15)
				)
				(justify left bottom)
				(hide yes)
			)
		)
		(property "License" "Apache-2.0"
			(at 280.67 99.06 0)
			(effects
				(font
					(size 1.27 1.27)
					(thickness 0.15)
				)
				(justify left bottom)
				(hide yes)
			)
		)
		(property "Author" "Antmicro"
			(at 283.21 99.06 0)
			(effects
				(font
					(size 1.27 1.27)
					(thickness 0.15)
				)
				(justify left bottom)
				(hide yes)
			)
		)
		(property "Val" "4k53"
			(at 256.794 116.84 90)
			(effects
				(font
					(size 1.27 1.27)
					(thickness 0.15)
				)
				(justify right)
			)
		)
		(property "Tolerance" "0.1%"
			(at 256.794 119.3799 90)
			(effects
				(font
					(size 1.27 1.27)
				)
				(justify right)
			)
		)
		(pin "1"
		)
		(pin "2"
		)
		(instances
			(project "OCuLink to 10GbE adapter"
				(path ""
					(reference "R57")
					(unit 1)
				)
			)
			(project "thunderbolt-to-10gbe-adapter"
				(path ""
					(reference "R206")
					(unit 1)
				)
			)
		)
	)
	(symbol
		(lib_id "antmicroInterfaceControllers:EZX710AT2_S_LMR5")
		(at 193.04 167.64 0)
		(unit 3)
		(exclude_from_sim no)
		(in_bom yes)
		(on_board yes)
		(dnp no)
		(fields_autoplaced yes)
		(property "Reference" "U14"
			(at 218.44 160.02 0)
			(effects
				(font
					(size 1.27 1.27)
					(thickness 0.15)
				)
			)
		)
		(property "Value" "EZX710AT2_S_LMR5"
			(at 269.24 172.72 0)
			(effects
				(font
					(size 1.27 1.27)
					(thickness 0.15)
				)
				(justify left bottom)
				(hide yes)
			)
		)
		(property "Footprint" "antmicro-footprints:FCBGA-503_22x22mm_Layout21x24_P1mm"
			(at 269.24 175.26 0)
			(effects
				(font
					(size 1.27 1.27)
					(thickness 0.15)
				)
				(justify left bottom)
				(hide yes)
			)
		)
		(property "Datasheet" "https://www.google.com/url?sa=t&source=web&rct=j&opi=89978449&url=https://cdrdv2-public.intel.com/596333/596333_X710-TM4_Datasheet_v_2_4.pdf&ved=2ahUKEwiSuv20_sCOAxXVCRAIHdxGO_UQFnoECBEQAQ&usg=AOvVaw1CjGyrGWE8ZvOdw4VBsY6U"
			(at 269.24 177.8 0)
			(effects
				(font
					(size 1.27 1.27)
					(thickness 0.15)
				)
				(justify left bottom)
				(hide yes)
			)
		)
		(property "Description" "Ethernet ICs Intel Ethernet Controller 10 Gigabit X7"
			(at 269.24 180.34 0)
			(effects
				(font
					(size 1.27 1.27)
					(thickness 0.15)
				)
				(justify left bottom)
				(hide yes)
			)
		)
		(property "MPN" "EZX710AT2 S LMR5"
			(at 218.44 162.56 0)
			(effects
				(font
					(size 1.27 1.27)
					(thickness 0.15)
				)
			)
		)
		(property "Manufacturer" "Intel"
			(at 269.24 182.88 0)
			(effects
				(font
					(size 1.27 1.27)
					(thickness 0.15)
				)
				(justify left bottom)
				(hide yes)
			)
		)
		(property "Author" "Antmicro"
			(at 269.24 185.42 0)
			(effects
				(font
					(size 1.27 1.27)
					(thickness 0.15)
				)
				(justify left bottom)
				(hide yes)
			)
		)
		(property "License" "Apache-2.0"
			(at 269.24 187.96 0)
			(effects
				(font
					(size 1.27 1.27)
					(thickness 0.15)
				)
				(justify left bottom)
				(hide yes)
			)
		)
		(pin "E39"
		)
		(pin "AD18"
		)
		(pin "AD2"
		)
		(pin "K32"
		)
		(pin "M32"
		)
		(pin "M30"
		)
		(pin "D8"
		)
		(pin "G23"
		)
		(pin "D4"
		)
		(pin "P16"
		)
		(pin "P18"
		)
		(pin "P20"
		)
		(pin "K40"
		)
		(pin "T20"
		)
		(pin "AC31"
		)
		(pin "E5"
		)
		(pin "AD10"
		)
		(pin "W1"
		)
		(pin "G41"
		)
		(pin "W3"
		)
		(pin "U1"
		)
		(pin "H42"
		)
		(pin "H38"
		)
		(pin "K10"
		)
		(pin "U31"
		)
		(pin "V32"
		)
		(pin "C21"
		)
		(pin "B42"
		)
		(pin "V24"
		)
		(pin "P24"
		)
		(pin "Y16"
		)
		(pin "D14"
		)
		(pin "L25"
		)
		(pin "E13"
		)
		(pin "P26"
		)
		(pin "B6"
		)
		(pin "R41"
		)
		(pin "AB32"
		)
		(pin "AB34"
		)
		(pin "R5"
		)
		(pin "T26"
		)
		(pin "AA19"
		)
		(pin "AA21"
		)
		(pin "L37"
		)
		(pin "H2"
		)
		(pin "F22"
		)
		(pin "E19"
		)
		(pin "A17"
		)
		(pin "G19"
		)
		(pin "G21"
		)
		(pin "H34"
		)
		(pin "H36"
		)
		(pin "A15"
		)
		(pin "A19"
		)
		(pin "R39"
		)
		(pin "W37"
		)
		(pin "W39"
		)
		(pin "Y14"
		)
		(pin "L5"
		)
		(pin "N3"
		)
		(pin "N1"
		)
		(pin "T4"
		)
		(pin "B18"
		)
		(pin "W31"
		)
		(pin "W33"
		)
		(pin "W35"
		)
		(pin "W41"
		)
		(pin "C19"
		)
		(pin "C5"
		)
		(pin "M42"
		)
		(pin "G37"
		)
		(pin "L39"
		)
		(pin "F4"
		)
		(pin "AD20"
		)
		(pin "G7"
		)
		(pin "T40"
		)
		(pin "J9"
		)
		(pin "AB18"
		)
		(pin "AA35"
		)
		(pin "H6"
		)
		(pin "M8"
		)
		(pin "A39"
		)
		(pin "P28"
		)
		(pin "Y30"
		)
		(pin "G5"
		)
		(pin "AD32"
		)
		(pin "AD8"
		)
		(pin "AB28"
		)
		(pin "H18"
		)
		(pin "H20"
		)
		(pin "J15"
		)
		(pin "H16"
		)
		(pin "P22"
		)
		(pin "M6"
		)
		(pin "E9"
		)
		(pin "H24"
		)
		(pin "K34"
		)
		(pin "K36"
		)
		(pin "K26"
		)
		(pin "B36"
		)
		(pin "C3"
		)
		(pin "AD22"
		)
		(pin "AA27"
		)
		(pin "V4"
		)
		(pin "B38"
		)
		(pin "D42"
		)
		(pin "F12"
		)
		(pin "AB16"
		)
		(pin "K8"
		)
		(pin "M10"
		)
		(pin "H14"
		)
		(pin "G13"
		)
		(pin "H30"
		)
		(pin "H32"
		)
		(pin "B24"
		)
		(pin "L23"
		)
		(pin "A33"
		)
		(pin "AC25"
		)
		(pin "AC27"
		)
		(pin "P32"
		)
		(pin "P30"
		)
		(pin "H4"
		)
		(pin "U25"
		)
		(pin "V12"
		)
		(pin "V14"
		)
		(pin "V16"
		)
		(pin "W9"
		)
		(pin "T8"
		)
		(pin "AA39"
		)
		(pin "M4"
		)
		(pin "AD24"
		)
		(pin "AD30"
		)
		(pin "U5"
		)
		(pin "U7"
		)
		(pin "AA41"
		)
		(pin "AA9"
		)
		(pin "E17"
		)
		(pin "V36"
		)
		(pin "T42"
		)
		(pin "U27"
		)
		(pin "F16"
		)
		(pin "A23"
		)
		(pin "Y18"
		)
		(pin "V2"
		)
		(pin "V8"
		)
		(pin "L35"
		)
		(pin "H40"
		)
		(pin "N5"
		)
		(pin "AA31"
		)
		(pin "C11"
		)
		(pin "C13"
		)
		(pin "B12"
		)
		(pin "B16"
		)
		(pin "P8"
		)
		(pin "A35"
		)
		(pin "T24"
		)
		(pin "Y38"
		)
		(pin "AC39"
		)
		(pin "J3"
		)
		(pin "U9"
		)
		(pin "K24"
		)
		(pin "AD40"
		)
		(pin "C1"
		)
		(pin "L13"
		)
		(pin "L15"
		)
		(pin "F8"
		)
		(pin "F6"
		)
		(pin "AA7"
		)
		(pin "W25"
		)
		(pin "V42"
		)
		(pin "N7"
		)
		(pin "R9"
		)
		(pin "Y2"
		)
		(pin "F24"
		)
		(pin "F26"
		)
		(pin "C35"
		)
		(pin "C37"
		)
		(pin "J25"
		)
		(pin "AC21"
		)
		(pin "AC23"
		)
		(pin "P42"
		)
		(pin "E11"
		)
		(pin "Y12"
		)
		(pin "A5"
		)
		(pin "V38"
		)
		(pin "AB12"
		)
		(pin "AB4"
		)
		(pin "AB40"
		)
		(pin "AD42"
		)
		(pin "AD6"
		)
		(pin "D10"
		)
		(pin "D2"
		)
		(pin "R23"
		)
		(pin "Y24"
		)
		(pin "T38"
		)
		(pin "AD14"
		)
		(pin "AC41"
		)
		(pin "AC7"
		)
		(pin "Y10"
		)
		(pin "U13"
		)
		(pin "U15"
		)
		(pin "W17"
		)
		(pin "W19"
		)
		(pin "W27"
		)
		(pin "M2"
		)
		(pin "L17"
		)
		(pin "N11"
		)
		(pin "H12"
		)
		(pin "B14"
		)
		(pin "G27"
		)
		(pin "G29"
		)
		(pin "K6"
		)
		(pin "AB42"
		)
		(pin "M24"
		)
		(pin "E7"
		)
		(pin "AC17"
		)
		(pin "AC19"
		)
		(pin "R31"
		)
		(pin "R29"
		)
		(pin "A31"
		)
		(pin "B22"
		)
		(pin "B32"
		)
		(pin "Y36"
		)
		(pin "Y4"
		)
		(pin "Y40"
		)
		(pin "R35"
		)
		(pin "T10"
		)
		(pin "T12"
		)
		(pin "J1"
		)
		(pin "V6"
		)
		(pin "A13"
		)
		(pin "W21"
		)
		(pin "L19"
		)
		(pin "Y6"
		)
		(pin "Y8"
		)
		(pin "A21"
		)
		(pin "G35"
		)
		(pin "G25"
		)
		(pin "C25"
		)
		(pin "C27"
		)
		(pin "J17"
		)
		(pin "K30"
		)
		(pin "W23"
		)
		(pin "M12"
		)
		(pin "M14"
		)
		(pin "M16"
		)
		(pin "D18"
		)
		(pin "K42"
		)
		(pin "T14"
		)
		(pin "T16"
		)
		(pin "T18"
		)
		(pin "T28"
		)
		(pin "U39"
		)
		(pin "N39"
		)
		(pin "U17"
		)
		(pin "U19"
		)
		(pin "R11"
		)
		(pin "T34"
		)
		(pin "P38"
		)
		(pin "E1"
		)
		(pin "C7"
		)
		(pin "C9"
		)
		(pin "F2"
		)
		(pin "J29"
		)
		(pin "J31"
		)
		(pin "U37"
		)
		(pin "AC9"
		)
		(pin "AD12"
		)
		(pin "P40"
		)
		(pin "K4"
		)
		(pin "N9"
		)
		(pin "M40"
		)
		(pin "E3"
		)
		(pin "F18"
		)
		(pin "F20"
		)
		(pin "T6"
		)
		(pin "U3"
		)
		(pin "C29"
		)
		(pin "J27"
		)
		(pin "AB26"
		)
		(pin "AB30"
		)
		(pin "AB2"
		)
		(pin "AA1"
		)
		(pin "P2"
		)
		(pin "R1"
		)
		(pin "R33"
		)
		(pin "AC1"
		)
		(pin "AC11"
		)
		(pin "AA5"
		)
		(pin "AC5"
		)
		(pin "AD4"
		)
		(pin "U41"
		)
		(pin "N19"
		)
		(pin "N21"
		)
		(pin "R37"
		)
		(pin "W5"
		)
		(pin "E25"
		)
		(pin "D22"
		)
		(pin "U29"
		)
		(pin "E29"
		)
		(pin "C33"
		)
		(pin "N33"
		)
		(pin "F14"
		)
		(pin "A29"
		)
		(pin "N35"
		)
		(pin "B34"
		)
		(pin "Y20"
		)
		(pin "AC29"
		)
		(pin "AC3"
		)
		(pin "U21"
		)
		(pin "W11"
		)
		(pin "U23"
		)
		(pin "N41"
		)
		(pin "P4"
		)
		(pin "AC35"
		)
		(pin "AD34"
		)
		(pin "AD38"
		)
		(pin "G39"
		)
		(pin "L11"
		)
		(pin "G11"
		)
		(pin "V26"
		)
		(pin "G31"
		)
		(pin "G33"
		)
		(pin "G9"
		)
		(pin "AA23"
		)
		(pin "AA25"
		)
		(pin "G15"
		)
		(pin "K2"
		)
		(pin "U35"
		)
		(pin "U33"
		)
		(pin "J23"
		)
		(pin "R3"
		)
		(pin "B2"
		)
		(pin "B20"
		)
		(pin "P34"
		)
		(pin "E37"
		)
		(pin "E27"
		)
		(pin "J7"
		)
		(pin "H10"
		)
		(pin "J5"
		)
		(pin "AD16"
		)
		(pin "M26"
		)
		(pin "D12"
		)
		(pin "C15"
		)
		(pin "C17"
		)
		(pin "L41"
		)
		(pin "B40"
		)
		(pin "E41"
		)
		(pin "B4"
		)
		(pin "B8"
		)
		(pin "K28"
		)
		(pin "D20"
		)
		(pin "L33"
		)
		(pin "AB24"
		)
		(pin "AC13"
		)
		(pin "AC15"
		)
		(pin "E21"
		)
		(pin "E23"
		)
		(pin "L3"
		)
		(pin "R7"
		)
		(pin "V40"
		)
		(pin "E33"
		)
		(pin "F40"
		)
		(pin "F42"
		)
		(pin "G3"
		)
		(pin "AA15"
		)
		(pin "AA17"
		)
		(pin "M22"
		)
		(pin "W7"
		)
		(pin "AD26"
		)
		(pin "J35"
		)
		(pin "J33"
		)
		(pin "M28"
		)
		(pin "F34"
		)
		(pin "F36"
		)
		(pin "K18"
		)
		(pin "N27"
		)
		(pin "V34"
		)
		(pin "L7"
		)
		(pin "M36"
		)
		(pin "D26"
		)
		(pin "D28"
		)
		(pin "D36"
		)
		(pin "D38"
		)
		(pin "D40"
		)
		(pin "E31"
		)
		(pin "L9"
		)
		(pin "T2"
		)
		(pin "A9"
		)
		(pin "Y26"
		)
		(pin "Y28"
		)
		(pin "Y32"
		)
		(pin "D6"
		)
		(pin "F38"
		)
		(pin "B10"
		)
		(pin "AA11"
		)
		(pin "AA13"
		)
		(pin "R21"
		)
		(pin "U11"
		)
		(pin "AA29"
		)
		(pin "AA3"
		)
		(pin "H26"
		)
		(pin "H28"
		)
		(pin "K12"
		)
		(pin "K14"
		)
		(pin "AB14"
		)
		(pin "AB20"
		)
		(pin "N23"
		)
		(pin "V10"
		)
		(pin "A11"
		)
		(pin "G1"
		)
		(pin "AB36"
		)
		(pin "AB38"
		)
		(pin "P36"
		)
		(pin "M38"
		)
		(pin "D34"
		)
		(pin "B28"
		)
		(pin "C39"
		)
		(pin "C23"
		)
		(pin "J11"
		)
		(pin "AB22"
		)
		(pin "T22"
		)
		(pin "V30"
		)
		(pin "L31"
		)
		(pin "J13"
		)
		(pin "N25"
		)
		(pin "N31"
		)
		(pin "N29"
		)
		(pin "H22"
		)
		(pin "G17"
		)
		(pin "N37"
		)
		(pin "AD36"
		)
		(pin "A27"
		)
		(pin "F10"
		)
		(pin "AD28"
		)
		(pin "L1"
		)
		(pin "E15"
		)
		(pin "A25"
		)
		(pin "L21"
		)
		(pin "N17"
		)
		(pin "A41"
		)
		(pin "L29"
		)
		(pin "A3"
		)
		(pin "A7"
		)
		(pin "T32"
		)
		(pin "T30"
		)
		(pin "P10"
		)
		(pin "P12"
		)
		(pin "P14"
		)
		(pin "J37"
		)
		(pin "M34"
		)
		(pin "R17"
		)
		(pin "R19"
		)
		(pin "N13"
		)
		(pin "N15"
		)
		(pin "R27"
		)
		(pin "J41"
		)
		(pin "D16"
		)
		(pin "D30"
		)
		(pin "E35"
		)
		(pin "B26"
		)
		(pin "F28"
		)
		(pin "F30"
		)
		(pin "F32"
		)
		(pin "J19"
		)
		(pin "J21"
		)
		(pin "K20"
		)
		(pin "M18"
		)
		(pin "M20"
		)
		(pin "W13"
		)
		(pin "W15"
		)
		(pin "AB10"
		)
		(pin "P6"
		)
		(pin "R25"
		)
		(pin "V22"
		)
		(pin "V18"
		)
		(pin "V20"
		)
		(pin "W29"
		)
		(pin "K22"
		)
		(pin "Y22"
		)
		(pin "AC33"
		)
		(pin "AC37"
		)
		(pin "Y42"
		)
		(pin "R13"
		)
		(pin "R15"
		)
		(pin "H8"
		)
		(pin "Y34"
		)
		(pin "T36"
		)
		(pin "V28"
		)
		(pin "AB6"
		)
		(pin "AB8"
		)
		(pin "D32"
		)
		(pin "J39"
		)
		(pin "L27"
		)
		(pin "C31"
		)
		(pin "C41"
		)
		(pin "D24"
		)
		(pin "K16"
		)
		(pin "K38"
		)
		(pin "B30"
		)
		(pin "AA33"
		)
		(pin "AA37"
		)
		(pin "A37"
		)
		(instances
			(project ""
				(path ""
					(reference "U9")
					(unit 3)
				)
			)
			(project "thunderbolt-to-10gbe-adapter"
				(path ""
					(reference "U14")
					(unit 3)
				)
			)
		)
	)
	(symbol
		(lib_id "antmicroCapacitors0402:C_100n_0402")
		(at 158.75 226.06 180)
		(unit 1)
		(exclude_from_sim no)
		(in_bom yes)
		(on_board yes)
		(dnp no)
		(property "Reference" "C286"
			(at 154.686 224.79 0)
			(effects
				(font
					(size 1.27 1.27)
					(thickness 0.15)
				)
				(justify left)
			)
		)
		(property "Value" "C_100n_0402"
			(at 143.51 203.2 0)
			(effects
				(font
					(size 1.27 1.27)
					(thickness 0.15)
				)
				(justify left bottom)
				(hide yes)
			)
		)
		(property "Footprint" "antmicro-footprints:C_0402_1005Metric"
			(at 143.51 200.66 0)
			(effects
				(font
					(size 1.27 1.27)
					(thickness 0.15)
				)
				(justify left bottom)
				(hide yes)
			)
		)
		(property "Datasheet" "https://www.murata.com/products/productdetail?partno=GRM155R61H104KE14%23"
			(at 143.51 198.12 0)
			(effects
				(font
					(size 1.27 1.27)
					(thickness 0.15)
				)
				(justify left bottom)
				(hide yes)
			)
		)
		(property "Description" "SMD Multilayer Ceramic Capacitor, 0.1 µF, 50 V, 0402 [1005 Metric], ± 10%, X5R, GRM Series"
			(at 158.75 226.06 0)
			(effects
				(font
					(size 1.27 1.27)
				)
				(hide yes)
			)
		)
		(property "MPN" "GRM155R61H104KE14D"
			(at 143.51 195.58 0)
			(effects
				(font
					(size 1.27 1.27)
					(thickness 0.15)
				)
				(justify left bottom)
				(hide yes)
			)
		)
		(property "Val" "100n"
			(at 157.734 224.79 0)
			(effects
				(font
					(size 1.27 1.27)
					(thickness 0.15)
				)
				(justify right)
			)
		)
		(property "Voltage" "50V"
			(at 143.51 215.9 0)
			(effects
				(font
					(size 1.27 1.27)
					(thickness 0.15)
				)
				(justify left bottom)
				(hide yes)
			)
		)
		(property "Dielectric" "X5R"
			(at 143.51 213.36 0)
			(effects
				(font
					(size 1.27 1.27)
					(thickness 0.15)
				)
				(justify left bottom)
				(hide yes)
			)
		)
		(property "Manufacturer" "Murata"
			(at 143.51 210.82 0)
			(effects
				(font
					(size 1.27 1.27)
					(thickness 0.15)
				)
				(justify left bottom)
				(hide yes)
			)
		)
		(property "License" "Apache-2.0"
			(at 143.51 208.28 0)
			(effects
				(font
					(size 1.27 1.27)
					(thickness 0.15)
				)
				(justify left bottom)
				(hide yes)
			)
		)
		(property "Author" "Antmicro"
			(at 143.51 205.74 0)
			(effects
				(font
					(size 1.27 1.27)
					(thickness 0.15)
				)
				(justify left bottom)
				(hide yes)
			)
		)
		(pin "2"
		)
		(pin "1"
		)
		(instances
			(project "OCuLink to 10GbE adapter"
				(path ""
					(reference "C69")
					(unit 1)
				)
			)
			(project "thunderbolt-to-10gbe-adapter"
				(path ""
					(reference "C286")
					(unit 1)
				)
			)
		)
	)
	(symbol
		(lib_id "antmicroResistors0402:R_0R_0402")
		(at 251.46 238.76 90)
		(unit 1)
		(exclude_from_sim no)
		(in_bom yes)
		(on_board yes)
		(dnp no)
		(property "Reference" "R205"
			(at 252.984 234.95 90)
			(effects
				(font
					(size 1.27 1.27)
					(thickness 0.15)
				)
				(justify right)
			)
		)
		(property "Value" "R_0R_0402"
			(at 264.16 218.44 0)
			(effects
				(font
					(size 1.27 1.27)
					(thickness 0.15)
				)
				(justify left bottom)
				(hide yes)
			)
		)
		(property "Footprint" "antmicro-footprints:R_0402_1005Metric"
			(at 266.7 218.44 0)
			(effects
				(font
					(size 1.27 1.27)
					(thickness 0.15)
				)
				(justify left bottom)
				(hide yes)
			)
		)
		(property "Datasheet" "https://industrial.panasonic.com/cdbs/www-data/pdf/RDA0000/AOA0000C301.pdf"
			(at 269.24 218.44 0)
			(effects
				(font
					(size 1.27 1.27)
					(thickness 0.15)
				)
				(justify left bottom)
				(hide yes)
			)
		)
		(property "Description" "SMD Chip Resistor, Jumper, 0 ohm, 100 mW, 0402 [1005 Metric], Thick Film, General Purpose"
			(at 251.46 238.76 0)
			(effects
				(font
					(size 1.27 1.27)
				)
				(hide yes)
			)
		)
		(property "MPN" "ERJ2GE0R00X"
			(at 271.78 218.44 0)
			(effects
				(font
					(size 1.27 1.27)
					(thickness 0.15)
				)
				(justify left bottom)
				(hide yes)
			)
		)
		(property "Manufacturer" "Panasonic"
			(at 274.32 218.44 0)
			(effects
				(font
					(size 1.27 1.27)
					(thickness 0.15)
				)
				(justify left bottom)
				(hide yes)
			)
		)
		(property "License" "Apache-2.0"
			(at 276.86 218.44 0)
			(effects
				(font
					(size 1.27 1.27)
					(thickness 0.15)
				)
				(justify left bottom)
				(hide yes)
			)
		)
		(property "Author" "Antmicro"
			(at 279.4 218.44 0)
			(effects
				(font
					(size 1.27 1.27)
					(thickness 0.15)
				)
				(justify left bottom)
				(hide yes)
			)
		)
		(property "Val" "0R"
			(at 252.984 237.49 90)
			(effects
				(font
					(size 1.27 1.27)
					(thickness 0.15)
				)
				(justify right)
			)
		)
		(property "Tolerance" "~"
			(at 261.62 218.44 0)
			(effects
				(font
					(size 1.27 1.27)
				)
				(justify left bottom)
				(hide yes)
			)
		)
		(property "Current" "1A"
			(at 281.94 218.44 0)
			(effects
				(font
					(size 1.27 1.27)
					(thickness 0.15)
				)
				(justify left bottom)
				(hide yes)
			)
		)
		(pin "1"
		)
		(pin "2"
		)
		(instances
			(project "OCuLink to 10GbE adapter"
				(path ""
					(reference "R74")
					(unit 1)
				)
			)
			(project "thunderbolt-to-10gbe-adapter"
				(path ""
					(reference "R205")
					(unit 1)
				)
			)
		)
	)
	(symbol
		(lib_id "antmicroResistors0402:R_3k3_0402")
		(at 137.16 165.1 90)
		(unit 1)
		(exclude_from_sim no)
		(in_bom yes)
		(on_board yes)
		(dnp no)
		(property "Reference" "R192"
			(at 138.684 161.29 90)
			(effects
				(font
					(size 1.27 1.27)
					(thickness 0.15)
				)
				(justify right)
			)
		)
		(property "Value" "R_3k3_0402"
			(at 149.86 144.78 0)
			(effects
				(font
					(size 1.27 1.27)
					(thickness 0.15)
				)
				(justify left bottom)
				(hide yes)
			)
		)
		(property "Footprint" "antmicro-footprints:R_0402_1005Metric"
			(at 152.4 144.78 0)
			(effects
				(font
					(size 1.27 1.27)
					(thickness 0.15)
				)
				(justify left bottom)
				(hide yes)
			)
		)
		(property "Datasheet" "https://www.bourns.com/docs/product-datasheets/cr.pdf"
			(at 154.94 144.78 0)
			(effects
				(font
					(size 1.27 1.27)
					(thickness 0.15)
				)
				(justify left bottom)
				(hide yes)
			)
		)
		(property "Description" "SMD Chip Resistor, 3.3 kohm, ± 1%, 63 mW, 0402 [1005 Metric], Thick Film, General Purpose"
			(at 137.16 165.1 0)
			(effects
				(font
					(size 1.27 1.27)
				)
				(hide yes)
			)
		)
		(property "MPN" "CR0402-FX-3301GLF"
			(at 157.48 144.78 0)
			(effects
				(font
					(size 1.27 1.27)
					(thickness 0.15)
				)
				(justify left bottom)
				(hide yes)
			)
		)
		(property "Manufacturer" "Bourns"
			(at 160.02 144.78 0)
			(effects
				(font
					(size 1.27 1.27)
					(thickness 0.15)
				)
				(justify left bottom)
				(hide yes)
			)
		)
		(property "License" "Apache-2.0"
			(at 162.56 144.78 0)
			(effects
				(font
					(size 1.27 1.27)
					(thickness 0.15)
				)
				(justify left bottom)
				(hide yes)
			)
		)
		(property "Author" "Antmicro"
			(at 165.1 144.78 0)
			(effects
				(font
					(size 1.27 1.27)
					(thickness 0.15)
				)
				(justify left bottom)
				(hide yes)
			)
		)
		(property "Val" "3k3"
			(at 138.684 163.83 90)
			(effects
				(font
					(size 1.27 1.27)
					(thickness 0.15)
				)
				(justify right)
			)
		)
		(property "Tolerance" "1%"
			(at 147.32 144.78 0)
			(effects
				(font
					(size 1.27 1.27)
				)
				(justify left bottom)
				(hide yes)
			)
		)
		(pin "2"
		)
		(pin "1"
		)
		(instances
			(project "OCuLink to 10GbE adapter"
				(path ""
					(reference "R61")
					(unit 1)
				)
			)
			(project "thunderbolt-to-10gbe-adapter"
				(path ""
					(reference "R192")
					(unit 1)
				)
			)
		)
	)
	(symbol
		(lib_id "antmicroResistors0402:R_1k_0402")
		(at 251.46 226.06 90)
		(unit 1)
		(exclude_from_sim no)
		(in_bom yes)
		(on_board yes)
		(dnp yes)
		(property "Reference" "R204"
			(at 252.984 222.25 90)
			(effects
				(font
					(size 1.27 1.27)
					(thickness 0.15)
				)
				(justify right)
			)
		)
		(property "Value" "R_1k_0402"
			(at 264.16 205.74 0)
			(effects
				(font
					(size 1.27 1.27)
					(thickness 0.15)
				)
				(justify left bottom)
				(hide yes)
			)
		)
		(property "Footprint" "antmicro-footprints:R_0402_1005Metric"
			(at 266.7 205.74 0)
			(effects
				(font
					(size 1.27 1.27)
					(thickness 0.15)
				)
				(justify left bottom)
				(hide yes)
			)
		)
		(property "Datasheet" "https://www.bourns.com/docs/product-datasheets/cr.pdf"
			(at 269.24 205.74 0)
			(effects
				(font
					(size 1.27 1.27)
					(thickness 0.15)
				)
				(justify left bottom)
				(hide yes)
			)
		)
		(property "Description" "SMD Chip Resistor, 1 kohm, ± 1%, 63 mW, 0402 [1005 Metric], Thick Film, General Purpose"
			(at 251.46 226.06 0)
			(effects
				(font
					(size 1.27 1.27)
				)
				(hide yes)
			)
		)
		(property "MPN" "CR0402-FX-1001GLF"
			(at 271.78 205.74 0)
			(effects
				(font
					(size 1.27 1.27)
					(thickness 0.15)
				)
				(justify left bottom)
				(hide yes)
			)
		)
		(property "Manufacturer" "Bourns"
			(at 274.32 205.74 0)
			(effects
				(font
					(size 1.27 1.27)
					(thickness 0.15)
				)
				(justify left bottom)
				(hide yes)
			)
		)
		(property "License" "Apache-2.0"
			(at 276.86 205.74 0)
			(effects
				(font
					(size 1.27 1.27)
					(thickness 0.15)
				)
				(justify left bottom)
				(hide yes)
			)
		)
		(property "Author" "Antmicro"
			(at 279.4 205.74 0)
			(effects
				(font
					(size 1.27 1.27)
					(thickness 0.15)
				)
				(justify left bottom)
				(hide yes)
			)
		)
		(property "Val" "1k"
			(at 252.984 224.79 90)
			(effects
				(font
					(size 1.27 1.27)
					(thickness 0.15)
				)
				(justify right)
			)
		)
		(property "Tolerance" "1%"
			(at 261.62 205.74 0)
			(effects
				(font
					(size 1.27 1.27)
				)
				(justify left bottom)
				(hide yes)
			)
		)
		(pin "2"
		)
		(pin "1"
		)
		(instances
			(project "OCuLink to 10GbE adapter"
				(path ""
					(reference "R72")
					(unit 1)
				)
			)
			(project "thunderbolt-to-10gbe-adapter"
				(path ""
					(reference "R204")
					(unit 1)
				)
			)
		)
	)
	(symbol
		(lib_id "antmicropower:GND")
		(at 53.34 236.22 0)
		(unit 1)
		(exclude_from_sim no)
		(in_bom yes)
		(on_board yes)
		(dnp no)
		(property "Reference" "#PWR0415"
			(at 62.23 238.76 0)
			(effects
				(font
					(size 1.27 1.27)
					(thickness 0.15)
				)
				(justify left bottom)
				(hide yes)
			)
		)
		(property "Value" "GND"
			(at 53.34 240.03 0)
			(effects
				(font
					(size 1.27 1.27)
					(thickness 0.15)
				)
			)
		)
		(property "Footprint" ""
			(at 62.23 243.84 0)
			(effects
				(font
					(size 1.27 1.27)
					(thickness 0.15)
				)
				(justify left bottom)
				(hide yes)
			)
		)
		(property "Datasheet" ""
			(at 62.23 248.92 0)
			(effects
				(font
					(size 1.27 1.27)
					(thickness 0.15)
				)
				(justify left bottom)
				(hide yes)
			)
		)
		(property "Description" ""
			(at 53.34 236.22 0)
			(effects
				(font
					(size 1.27 1.27)
				)
				(hide yes)
			)
		)
		(property "Author" "Antmicro"
			(at 62.23 243.84 0)
			(effects
				(font
					(size 1.27 1.27)
					(thickness 0.15)
				)
				(justify left bottom)
				(hide yes)
			)
		)
		(property "License" "Apache-2.0"
			(at 62.23 246.38 0)
			(effects
				(font
					(size 1.27 1.27)
					(thickness 0.15)
				)
				(justify left bottom)
				(hide yes)
			)
		)
		(pin "1"
		)
		(instances
			(project "OCuLink to 10GbE adapter"
				(path ""
					(reference "#PWR091")
					(unit 1)
				)
			)
			(project "thunderbolt-to-10gbe-adapter"
				(path ""
					(reference "#PWR0415")
					(unit 1)
				)
			)
		)
	)
	(symbol
		(lib_id "antmicropower:GND")
		(at 142.24 236.22 0)
		(unit 1)
		(exclude_from_sim no)
		(in_bom yes)
		(on_board yes)
		(dnp no)
		(property "Reference" "#PWR0420"
			(at 151.13 238.76 0)
			(effects
				(font
					(size 1.27 1.27)
					(thickness 0.15)
				)
				(justify left bottom)
				(hide yes)
			)
		)
		(property "Value" "GND"
			(at 142.24 240.03 0)
			(effects
				(font
					(size 1.27 1.27)
					(thickness 0.15)
				)
			)
		)
		(property "Footprint" ""
			(at 151.13 243.84 0)
			(effects
				(font
					(size 1.27 1.27)
					(thickness 0.15)
				)
				(justify left bottom)
				(hide yes)
			)
		)
		(property "Datasheet" ""
			(at 151.13 248.92 0)
			(effects
				(font
					(size 1.27 1.27)
					(thickness 0.15)
				)
				(justify left bottom)
				(hide yes)
			)
		)
		(property "Description" ""
			(at 142.24 236.22 0)
			(effects
				(font
					(size 1.27 1.27)
				)
				(hide yes)
			)
		)
		(property "Author" "Antmicro"
			(at 151.13 243.84 0)
			(effects
				(font
					(size 1.27 1.27)
					(thickness 0.15)
				)
				(justify left bottom)
				(hide yes)
			)
		)
		(property "License" "Apache-2.0"
			(at 151.13 246.38 0)
			(effects
				(font
					(size 1.27 1.27)
					(thickness 0.15)
				)
				(justify left bottom)
				(hide yes)
			)
		)
		(pin "1"
		)
		(instances
			(project "OCuLink to 10GbE adapter"
				(path ""
					(reference "#PWR094")
					(unit 1)
				)
			)
			(project "thunderbolt-to-10gbe-adapter"
				(path ""
					(reference "#PWR0420")
					(unit 1)
				)
			)
		)
	)
	(symbol
		(lib_id "antmicropower:GND")
		(at 251.46 241.3 0)
		(unit 1)
		(exclude_from_sim no)
		(in_bom yes)
		(on_board yes)
		(dnp no)
		(property "Reference" "#PWR0424"
			(at 260.35 243.84 0)
			(effects
				(font
					(size 1.27 1.27)
					(thickness 0.15)
				)
				(justify left bottom)
				(hide yes)
			)
		)
		(property "Value" "GND"
			(at 251.46 245.11 0)
			(effects
				(font
					(size 1.27 1.27)
					(thickness 0.15)
				)
			)
		)
		(property "Footprint" ""
			(at 260.35 248.92 0)
			(effects
				(font
					(size 1.27 1.27)
					(thickness 0.15)
				)
				(justify left bottom)
				(hide yes)
			)
		)
		(property "Datasheet" ""
			(at 260.35 254 0)
			(effects
				(font
					(size 1.27 1.27)
					(thickness 0.15)
				)
				(justify left bottom)
				(hide yes)
			)
		)
		(property "Description" ""
			(at 251.46 241.3 0)
			(effects
				(font
					(size 1.27 1.27)
				)
				(hide yes)
			)
		)
		(property "Author" "Antmicro"
			(at 260.35 248.92 0)
			(effects
				(font
					(size 1.27 1.27)
					(thickness 0.15)
				)
				(justify left bottom)
				(hide yes)
			)
		)
		(property "License" "Apache-2.0"
			(at 260.35 251.46 0)
			(effects
				(font
					(size 1.27 1.27)
					(thickness 0.15)
				)
				(justify left bottom)
				(hide yes)
			)
		)
		(pin "1"
		)
		(instances
			(project "OCuLink to 10GbE adapter"
				(path ""
					(reference "#PWR0255")
					(unit 1)
				)
			)
			(project "thunderbolt-to-10gbe-adapter"
				(path ""
					(reference "#PWR0424")
					(unit 1)
				)
			)
		)
	)
	(symbol
		(lib_id "antmicropower:PWR_FLAG")
		(at 58.42 214.63 0)
		(unit 1)
		(exclude_from_sim no)
		(in_bom yes)
		(on_board yes)
		(dnp no)
		(property "Reference" "#FLG032"
			(at 58.42 212.725 0)
			(effects
				(font
					(size 1.27 1.27)
				)
				(hide yes)
			)
		)
		(property "Value" "PWR_FLAG"
			(at 58.42 210.82 0)
			(effects
				(font
					(size 1.27 1.27)
				)
			)
		)
		(property "Footprint" ""
			(at 58.42 214.63 0)
			(effects
				(font
					(size 1.27 1.27)
				)
				(hide yes)
			)
		)
		(property "Datasheet" ""
			(at 58.42 214.63 0)
			(effects
				(font
					(size 1.27 1.27)
				)
				(hide yes)
			)
		)
		(property "Description" ""
			(at 58.42 214.63 0)
			(effects
				(font
					(size 1.27 1.27)
				)
				(hide yes)
			)
		)
		(pin "1"
		)
		(instances
			(project "OCuLink to 10GbE adapter"
				(path ""
					(reference "#FLG011")
					(unit 1)
				)
			)
			(project "thunderbolt-to-10gbe-adapter"
				(path ""
					(reference "#FLG032")
					(unit 1)
				)
			)
		)
	)
	(symbol
		(lib_id "antmicroResistors0402:R_3k3_0402")
		(at 129.54 165.1 90)
		(unit 1)
		(exclude_from_sim no)
		(in_bom yes)
		(on_board yes)
		(dnp no)
		(property "Reference" "R190"
			(at 131.064 161.29 90)
			(effects
				(font
					(size 1.27 1.27)
					(thickness 0.15)
				)
				(justify right)
			)
		)
		(property "Value" "R_3k3_0402"
			(at 142.24 144.78 0)
			(effects
				(font
					(size 1.27 1.27)
					(thickness 0.15)
				)
				(justify left bottom)
				(hide yes)
			)
		)
		(property "Footprint" "antmicro-footprints:R_0402_1005Metric"
			(at 144.78 144.78 0)
			(effects
				(font
					(size 1.27 1.27)
					(thickness 0.15)
				)
				(justify left bottom)
				(hide yes)
			)
		)
		(property "Datasheet" "https://www.bourns.com/docs/product-datasheets/cr.pdf"
			(at 147.32 144.78 0)
			(effects
				(font
					(size 1.27 1.27)
					(thickness 0.15)
				)
				(justify left bottom)
				(hide yes)
			)
		)
		(property "Description" "SMD Chip Resistor, 3.3 kohm, ± 1%, 63 mW, 0402 [1005 Metric], Thick Film, General Purpose"
			(at 129.54 165.1 0)
			(effects
				(font
					(size 1.27 1.27)
				)
				(hide yes)
			)
		)
		(property "MPN" "CR0402-FX-3301GLF"
			(at 149.86 144.78 0)
			(effects
				(font
					(size 1.27 1.27)
					(thickness 0.15)
				)
				(justify left bottom)
				(hide yes)
			)
		)
		(property "Manufacturer" "Bourns"
			(at 152.4 144.78 0)
			(effects
				(font
					(size 1.27 1.27)
					(thickness 0.15)
				)
				(justify left bottom)
				(hide yes)
			)
		)
		(property "License" "Apache-2.0"
			(at 154.94 144.78 0)
			(effects
				(font
					(size 1.27 1.27)
					(thickness 0.15)
				)
				(justify left bottom)
				(hide yes)
			)
		)
		(property "Author" "Antmicro"
			(at 157.48 144.78 0)
			(effects
				(font
					(size 1.27 1.27)
					(thickness 0.15)
				)
				(justify left bottom)
				(hide yes)
			)
		)
		(property "Val" "3k3"
			(at 131.064 163.83 90)
			(effects
				(font
					(size 1.27 1.27)
					(thickness 0.15)
				)
				(justify right)
			)
		)
		(property "Tolerance" "1%"
			(at 139.7 144.78 0)
			(effects
				(font
					(size 1.27 1.27)
				)
				(justify left bottom)
				(hide yes)
			)
		)
		(pin "2"
		)
		(pin "1"
		)
		(instances
			(project "OCuLink to 10GbE adapter"
				(path ""
					(reference "R60")
					(unit 1)
				)
			)
			(project "thunderbolt-to-10gbe-adapter"
				(path ""
					(reference "R190")
					(unit 1)
				)
			)
		)
	)
	(symbol
		(lib_id "antmicropower:GND")
		(at 38.1 236.22 0)
		(unit 1)
		(exclude_from_sim no)
		(in_bom yes)
		(on_board yes)
		(dnp no)
		(property "Reference" "#PWR0414"
			(at 46.99 238.76 0)
			(effects
				(font
					(size 1.27 1.27)
					(thickness 0.15)
				)
				(justify left bottom)
				(hide yes)
			)
		)
		(property "Value" "GND"
			(at 38.1 240.03 0)
			(effects
				(font
					(size 1.27 1.27)
					(thickness 0.15)
				)
			)
		)
		(property "Footprint" ""
			(at 46.99 243.84 0)
			(effects
				(font
					(size 1.27 1.27)
					(thickness 0.15)
				)
				(justify left bottom)
				(hide yes)
			)
		)
		(property "Datasheet" ""
			(at 46.99 248.92 0)
			(effects
				(font
					(size 1.27 1.27)
					(thickness 0.15)
				)
				(justify left bottom)
				(hide yes)
			)
		)
		(property "Description" ""
			(at 38.1 236.22 0)
			(effects
				(font
					(size 1.27 1.27)
				)
				(hide yes)
			)
		)
		(property "Author" "Antmicro"
			(at 46.99 243.84 0)
			(effects
				(font
					(size 1.27 1.27)
					(thickness 0.15)
				)
				(justify left bottom)
				(hide yes)
			)
		)
		(property "License" "Apache-2.0"
			(at 46.99 246.38 0)
			(effects
				(font
					(size 1.27 1.27)
					(thickness 0.15)
				)
				(justify left bottom)
				(hide yes)
			)
		)
		(pin "1"
		)
		(instances
			(project "OCuLink to 10GbE adapter"
				(path ""
					(reference "#PWR090")
					(unit 1)
				)
			)
			(project "thunderbolt-to-10gbe-adapter"
				(path ""
					(reference "#PWR0414")
					(unit 1)
				)
			)
		)
	)
	(symbol
		(lib_id "antmicroResistors0402:R_3k3_0402")
		(at 121.92 165.1 90)
		(unit 1)
		(exclude_from_sim no)
		(in_bom yes)
		(on_board yes)
		(dnp no)
		(property "Reference" "R187"
			(at 123.444 161.29 90)
			(effects
				(font
					(size 1.27 1.27)
					(thickness 0.15)
				)
				(justify right)
			)
		)
		(property "Value" "R_3k3_0402"
			(at 134.62 144.78 0)
			(effects
				(font
					(size 1.27 1.27)
					(thickness 0.15)
				)
				(justify left bottom)
				(hide yes)
			)
		)
		(property "Footprint" "antmicro-footprints:R_0402_1005Metric"
			(at 137.16 144.78 0)
			(effects
				(font
					(size 1.27 1.27)
					(thickness 0.15)
				)
				(justify left bottom)
				(hide yes)
			)
		)
		(property "Datasheet" "https://www.bourns.com/docs/product-datasheets/cr.pdf"
			(at 139.7 144.78 0)
			(effects
				(font
					(size 1.27 1.27)
					(thickness 0.15)
				)
				(justify left bottom)
				(hide yes)
			)
		)
		(property "Description" "SMD Chip Resistor, 3.3 kohm, ± 1%, 63 mW, 0402 [1005 Metric], Thick Film, General Purpose"
			(at 121.92 165.1 0)
			(effects
				(font
					(size 1.27 1.27)
				)
				(hide yes)
			)
		)
		(property "MPN" "CR0402-FX-3301GLF"
			(at 142.24 144.78 0)
			(effects
				(font
					(size 1.27 1.27)
					(thickness 0.15)
				)
				(justify left bottom)
				(hide yes)
			)
		)
		(property "Manufacturer" "Bourns"
			(at 144.78 144.78 0)
			(effects
				(font
					(size 1.27 1.27)
					(thickness 0.15)
				)
				(justify left bottom)
				(hide yes)
			)
		)
		(property "License" "Apache-2.0"
			(at 147.32 144.78 0)
			(effects
				(font
					(size 1.27 1.27)
					(thickness 0.15)
				)
				(justify left bottom)
				(hide yes)
			)
		)
		(property "Author" "Antmicro"
			(at 149.86 144.78 0)
			(effects
				(font
					(size 1.27 1.27)
					(thickness 0.15)
				)
				(justify left bottom)
				(hide yes)
			)
		)
		(property "Val" "3k3"
			(at 123.444 163.83 90)
			(effects
				(font
					(size 1.27 1.27)
					(thickness 0.15)
				)
				(justify right)
			)
		)
		(property "Tolerance" "1%"
			(at 132.08 144.78 0)
			(effects
				(font
					(size 1.27 1.27)
				)
				(justify left bottom)
				(hide yes)
			)
		)
		(pin "2"
		)
		(pin "1"
		)
		(instances
			(project "OCuLink to 10GbE adapter"
				(path ""
					(reference "R59")
					(unit 1)
				)
			)
			(project "thunderbolt-to-10gbe-adapter"
				(path ""
					(reference "R187")
					(unit 1)
				)
			)
		)
	)
	(symbol
		(lib_id "antmicroResistors0402:R_3k3_0402")
		(at 160.02 165.1 90)
		(unit 1)
		(exclude_from_sim no)
		(in_bom yes)
		(on_board yes)
		(dnp no)
		(property "Reference" "R199"
			(at 161.544 161.29 90)
			(effects
				(font
					(size 1.27 1.27)
					(thickness 0.15)
				)
				(justify right)
			)
		)
		(property "Value" "R_3k3_0402"
			(at 172.72 144.78 0)
			(effects
				(font
					(size 1.27 1.27)
					(thickness 0.15)
				)
				(justify left bottom)
				(hide yes)
			)
		)
		(property "Footprint" "antmicro-footprints:R_0402_1005Metric"
			(at 175.26 144.78 0)
			(effects
				(font
					(size 1.27 1.27)
					(thickness 0.15)
				)
				(justify left bottom)
				(hide yes)
			)
		)
		(property "Datasheet" "https://www.bourns.com/docs/product-datasheets/cr.pdf"
			(at 177.8 144.78 0)
			(effects
				(font
					(size 1.27 1.27)
					(thickness 0.15)
				)
				(justify left bottom)
				(hide yes)
			)
		)
		(property "Description" "SMD Chip Resistor, 3.3 kohm, ± 1%, 63 mW, 0402 [1005 Metric], Thick Film, General Purpose"
			(at 160.02 165.1 0)
			(effects
				(font
					(size 1.27 1.27)
				)
				(hide yes)
			)
		)
		(property "MPN" "CR0402-FX-3301GLF"
			(at 180.34 144.78 0)
			(effects
				(font
					(size 1.27 1.27)
					(thickness 0.15)
				)
				(justify left bottom)
				(hide yes)
			)
		)
		(property "Manufacturer" "Bourns"
			(at 182.88 144.78 0)
			(effects
				(font
					(size 1.27 1.27)
					(thickness 0.15)
				)
				(justify left bottom)
				(hide yes)
			)
		)
		(property "License" "Apache-2.0"
			(at 185.42 144.78 0)
			(effects
				(font
					(size 1.27 1.27)
					(thickness 0.15)
				)
				(justify left bottom)
				(hide yes)
			)
		)
		(property "Author" "Antmicro"
			(at 187.96 144.78 0)
			(effects
				(font
					(size 1.27 1.27)
					(thickness 0.15)
				)
				(justify left bottom)
				(hide yes)
			)
		)
		(property "Val" "3k3"
			(at 161.544 163.83 90)
			(effects
				(font
					(size 1.27 1.27)
					(thickness 0.15)
				)
				(justify right)
			)
		)
		(property "Tolerance" "1%"
			(at 170.18 144.78 0)
			(effects
				(font
					(size 1.27 1.27)
				)
				(justify left bottom)
				(hide yes)
			)
		)
		(pin "2"
		)
		(pin "1"
		)
		(instances
			(project "OCuLink to 10GbE adapter"
				(path ""
					(reference "R64")
					(unit 1)
				)
			)
			(project "thunderbolt-to-10gbe-adapter"
				(path ""
					(reference "R199")
					(unit 1)
				)
			)
		)
	)
	(symbol
		(lib_id "antmicropower:+3V3")
		(at 38.1 214.63 0)
		(unit 1)
		(exclude_from_sim no)
		(in_bom yes)
		(on_board yes)
		(dnp no)
		(property "Reference" "#PWR0413"
			(at 53.34 214.63 0)
			(effects
				(font
					(size 1.27 1.27)
					(thickness 0.15)
				)
				(justify left bottom)
				(hide yes)
			)
		)
		(property "Value" "+3V3"
			(at 38.1 210.82 0)
			(effects
				(font
					(size 1.27 1.27)
					(thickness 0.15)
				)
			)
		)
		(property "Footprint" ""
			(at 53.34 222.25 0)
			(effects
				(font
					(size 1.27 1.27)
					(thickness 0.15)
				)
				(justify left bottom)
				(hide yes)
			)
		)
		(property "Datasheet" ""
			(at 53.34 224.79 0)
			(effects
				(font
					(size 1.27 1.27)
					(thickness 0.15)
				)
				(justify left bottom)
				(hide yes)
			)
		)
		(property "Description" ""
			(at 38.1 214.63 0)
			(effects
				(font
					(size 1.27 1.27)
				)
				(hide yes)
			)
		)
		(property "Author" "Antmicro"
			(at 53.34 217.17 0)
			(effects
				(font
					(size 1.27 1.27)
					(thickness 0.15)
				)
				(justify left bottom)
				(hide yes)
			)
		)
		(property "License" "Apache-2.0"
			(at 53.34 219.71 0)
			(effects
				(font
					(size 1.27 1.27)
					(thickness 0.15)
				)
				(justify left bottom)
				(hide yes)
			)
		)
		(pin "1"
		)
		(instances
			(project "OCuLink to 10GbE adapter"
				(path ""
					(reference "#PWR089")
					(unit 1)
				)
			)
			(project "thunderbolt-to-10gbe-adapter"
				(path ""
					(reference "#PWR0413")
					(unit 1)
				)
			)
		)
	)
	(symbol
		(lib_id "antmicroResistors0402:R_0R_0402")
		(at 153.67 198.12 0)
		(unit 1)
		(exclude_from_sim no)
		(in_bom yes)
		(on_board yes)
		(dnp no)
		(property "Reference" "R196"
			(at 153.67 196.85 0)
			(effects
				(font
					(size 1.27 1.27)
					(thickness 0.15)
				)
				(justify right)
			)
		)
		(property "Value" "R_0R_0402"
			(at 173.99 210.82 0)
			(effects
				(font
					(size 1.27 1.27)
					(thickness 0.15)
				)
				(justify left bottom)
				(hide yes)
			)
		)
		(property "Footprint" "antmicro-footprints:R_0402_1005Metric"
			(at 173.99 213.36 0)
			(effects
				(font
					(size 1.27 1.27)
					(thickness 0.15)
				)
				(justify left bottom)
				(hide yes)
			)
		)
		(property "Datasheet" "https://industrial.panasonic.com/cdbs/www-data/pdf/RDA0000/AOA0000C301.pdf"
			(at 173.99 215.9 0)
			(effects
				(font
					(size 1.27 1.27)
					(thickness 0.15)
				)
				(justify left bottom)
				(hide yes)
			)
		)
		(property "Description" "SMD Chip Resistor, Jumper, 0 ohm, 100 mW, 0402 [1005 Metric], Thick Film, General Purpose"
			(at 153.67 198.12 0)
			(effects
				(font
					(size 1.27 1.27)
				)
				(hide yes)
			)
		)
		(property "MPN" "ERJ2GE0R00X"
			(at 173.99 218.44 0)
			(effects
				(font
					(size 1.27 1.27)
					(thickness 0.15)
				)
				(justify left bottom)
				(hide yes)
			)
		)
		(property "Manufacturer" "Panasonic"
			(at 173.99 220.98 0)
			(effects
				(font
					(size 1.27 1.27)
					(thickness 0.15)
				)
				(justify left bottom)
				(hide yes)
			)
		)
		(property "License" "Apache-2.0"
			(at 173.99 223.52 0)
			(effects
				(font
					(size 1.27 1.27)
					(thickness 0.15)
				)
				(justify left bottom)
				(hide yes)
			)
		)
		(property "Author" "Antmicro"
			(at 173.99 226.06 0)
			(effects
				(font
					(size 1.27 1.27)
					(thickness 0.15)
				)
				(justify left bottom)
				(hide yes)
			)
		)
		(property "Val" "0R"
			(at 158.75 196.85 0)
			(effects
				(font
					(size 1.27 1.27)
					(thickness 0.15)
				)
				(justify left)
			)
		)
		(property "Tolerance" "~"
			(at 173.99 208.28 0)
			(effects
				(font
					(size 1.27 1.27)
				)
				(justify left bottom)
				(hide yes)
			)
		)
		(property "Current" "1A"
			(at 173.99 228.6 0)
			(effects
				(font
					(size 1.27 1.27)
					(thickness 0.15)
				)
				(justify left bottom)
				(hide yes)
			)
		)
		(pin "1"
		)
		(pin "2"
		)
		(instances
			(project ""
				(path ""
					(reference "R69")
					(unit 1)
				)
			)
			(project "thunderbolt-to-10gbe-adapter"
				(path ""
					(reference "R196")
					(unit 1)
				)
			)
		)
	)
	(symbol
		(lib_id "antmicroResistors0402:R_1k_0402")
		(at 261.62 226.06 90)
		(unit 1)
		(exclude_from_sim no)
		(in_bom yes)
		(on_board yes)
		(dnp yes)
		(property "Reference" "R207"
			(at 263.144 222.25 90)
			(effects
				(font
					(size 1.27 1.27)
					(thickness 0.15)
				)
				(justify right)
			)
		)
		(property "Value" "R_1k_0402"
			(at 274.32 205.74 0)
			(effects
				(font
					(size 1.27 1.27)
					(thickness 0.15)
				)
				(justify left bottom)
				(hide yes)
			)
		)
		(property "Footprint" "antmicro-footprints:R_0402_1005Metric"
			(at 276.86 205.74 0)
			(effects
				(font
					(size 1.27 1.27)
					(thickness 0.15)
				)
				(justify left bottom)
				(hide yes)
			)
		)
		(property "Datasheet" "https://www.bourns.com/docs/product-datasheets/cr.pdf"
			(at 279.4 205.74 0)
			(effects
				(font
					(size 1.27 1.27)
					(thickness 0.15)
				)
				(justify left bottom)
				(hide yes)
			)
		)
		(property "Description" "SMD Chip Resistor, 1 kohm, ± 1%, 63 mW, 0402 [1005 Metric], Thick Film, General Purpose"
			(at 261.62 226.06 0)
			(effects
				(font
					(size 1.27 1.27)
				)
				(hide yes)
			)
		)
		(property "MPN" "CR0402-FX-1001GLF"
			(at 281.94 205.74 0)
			(effects
				(font
					(size 1.27 1.27)
					(thickness 0.15)
				)
				(justify left bottom)
				(hide yes)
			)
		)
		(property "Manufacturer" "Bourns"
			(at 284.48 205.74 0)
			(effects
				(font
					(size 1.27 1.27)
					(thickness 0.15)
				)
				(justify left bottom)
				(hide yes)
			)
		)
		(property "License" "Apache-2.0"
			(at 287.02 205.74 0)
			(effects
				(font
					(size 1.27 1.27)
					(thickness 0.15)
				)
				(justify left bottom)
				(hide yes)
			)
		)
		(property "Author" "Antmicro"
			(at 289.56 205.74 0)
			(effects
				(font
					(size 1.27 1.27)
					(thickness 0.15)
				)
				(justify left bottom)
				(hide yes)
			)
		)
		(property "Val" "1k"
			(at 263.144 224.79 90)
			(effects
				(font
					(size 1.27 1.27)
					(thickness 0.15)
				)
				(justify right)
			)
		)
		(property "Tolerance" "1%"
			(at 271.78 205.74 0)
			(effects
				(font
					(size 1.27 1.27)
				)
				(justify left bottom)
				(hide yes)
			)
		)
		(pin "2"
		)
		(pin "1"
		)
		(instances
			(project "OCuLink to 10GbE adapter"
				(path ""
					(reference "R73")
					(unit 1)
				)
			)
			(project "thunderbolt-to-10gbe-adapter"
				(path ""
					(reference "R207")
					(unit 1)
				)
			)
		)
	)
)
